%FSTAX23Y23*%
%MOIN*%
%SFA1B1*%

%IPPOS*%
%ADD142C,0.120000*%
%ADD170C,0.061020*%
%ADD172C,0.075000*%
%ADD173C,0.098430*%
%ADD175O,0.177170X0.088580*%
%ADD176O,0.088580X0.177170*%
%ADD181C,0.016000*%
%ADD183C,0.200000*%
%LNtimingcard_pcb-1*%
%LPD*%
G36*
X07082Y04353D02*
Y00505D01*
X03109*
Y00225*
X02289*
Y0031*
X02257Y00342*
X02229*
X02197Y0031*
Y00225*
X01776*
Y00352*
X01781Y00353*
X01782Y00352*
X01782Y00348*
X01786Y00343*
X01791Y00339*
X01797Y00338*
X01804Y00339*
X01809Y00343*
X01812Y00348*
X01814Y00355*
X01812Y00361*
X01809Y00366*
X01804Y0037*
X01797Y00371*
X01791Y0037*
X01786Y00366*
X01782Y00361*
X01782Y00357*
X01781Y00357*
X01776Y00357*
Y00465*
X0173Y00511*
X01658*
X01613Y00466*
Y00312*
X01316*
Y00508*
X00576*
Y00184*
X00002*
Y04349*
X00006Y04353*
X07082*
G37*
%LNtimingcard_pcb-2*%
%LPC*%
G36*
X0257Y04299D02*
X02564Y04298D01*
X02559Y04294*
X02555Y04289*
X02554Y04283*
X02555Y04276*
X02559Y04271*
X02564Y04267*
X0257Y04266*
X02577Y04267*
X02582Y04271*
X02585Y04276*
X02587Y04283*
X02585Y04289*
X02582Y04294*
X02577Y04298*
X0257Y04299*
G37*
G36*
X01294Y04272D02*
X01288Y04271D01*
X01283Y04267*
X01279Y04262*
X01278Y04256*
X01279Y04249*
X01283Y04244*
X01288Y0424*
X01294Y04239*
X01301Y0424*
X01306Y04244*
X01309Y04249*
X01311Y04256*
X01309Y04262*
X01306Y04267*
X01301Y04271*
X01294Y04272*
G37*
G36*
X02078Y04293D02*
X02007D01*
Y04222*
X02078*
Y04293*
G37*
G36*
X01493Y04289D02*
X01422D01*
Y04218*
X01493*
Y04289*
G37*
G36*
X01557Y04245D02*
X01551Y04244D01*
X01546Y0424*
X01542Y04235*
X01541Y04229*
X01542Y04222*
X01546Y04217*
X01551Y04213*
X01557Y04212*
X01564Y04213*
X01569Y04217*
X01572Y04222*
X01574Y04229*
X01572Y04235*
X01569Y0424*
X01564Y04244*
X01557Y04245*
G37*
G36*
X01345Y04191D02*
X01339Y0419D01*
X01333Y04186*
X0133Y04181*
X01329Y04175*
X0133Y04168*
X01333Y04163*
X01339Y0416*
X01345Y04158*
X01351Y0416*
X01357Y04163*
X0136Y04168*
X01361Y04175*
X0136Y04181*
X01357Y04186*
X01351Y0419*
X01345Y04191*
G37*
G36*
X01569Y04187D02*
X01563Y04186D01*
X01558Y04182*
X01554Y04177*
X01553Y04171*
X01554Y04165*
X01558Y04159*
X01563Y04156*
X01569Y04154*
X01576Y04156*
X01581Y04159*
X01584Y04165*
X01586Y04171*
X01584Y04177*
X01581Y04182*
X01576Y04186*
X01569Y04187*
G37*
G36*
X01779Y04172D02*
X01773Y04171D01*
X01768Y04167*
X01764Y04162*
X01763Y04156*
X01764Y04149*
X01768Y04144*
X01773Y0414*
X01779Y04139*
X01786Y0414*
X01791Y04144*
X01794Y04149*
X01796Y04156*
X01794Y04162*
X01791Y04167*
X01786Y04171*
X01779Y04172*
G37*
G36*
X02043Y04193D02*
X02034Y04192D01*
X02025Y04188*
X02017Y04183*
X02012Y04175*
X02008Y04167*
X02007Y04157*
X02008Y04148*
X02012Y04139*
X02017Y04132*
X02025Y04126*
X02034Y04123*
X02043Y04122*
X02052Y04123*
X02061Y04126*
X02068Y04132*
X02074Y04139*
X02077Y04148*
X02079Y04157*
X02077Y04167*
X02074Y04175*
X02068Y04183*
X02061Y04188*
X02052Y04192*
X02043Y04193*
G37*
G36*
X01457Y04189D02*
X01448Y04188D01*
X01439Y04184*
X01432Y04179*
X01426Y04171*
X01423Y04163*
X01421Y04153*
X01423Y04144*
X01426Y04136*
X01432Y04128*
X01439Y04122*
X01448Y04119*
X01457Y04118*
X01466Y04119*
X01475Y04122*
X01483Y04128*
X01488Y04136*
X01492Y04144*
X01493Y04153*
X01492Y04163*
X01488Y04171*
X01483Y04179*
X01475Y04184*
X01466Y04188*
X01457Y04189*
G37*
G36*
X03958Y04152D02*
X03951Y04151D01*
X03945Y04148*
X03939Y04144*
X03935Y04139*
X03933Y04132*
X03932Y04126*
X03933Y04119*
X03935Y04113*
X03939Y04107*
X03945Y04103*
X03951Y04101*
X03958Y041*
X03964Y04101*
X03971Y04103*
X03976Y04107*
X0398Y04113*
X03983Y04119*
X03984Y04126*
X03983Y04132*
X0398Y04139*
X03976Y04144*
X03971Y04148*
X03964Y04151*
X03958Y04152*
G37*
G36*
X03784D02*
X03778Y04151D01*
X03771Y04148*
X03766Y04144*
X03762Y04139*
X03759Y04132*
X03758Y04126*
X03759Y04119*
X03762Y04113*
X03766Y04107*
X03771Y04103*
X03778Y04101*
X03784Y041*
X03791Y04101*
X03797Y04103*
X03803Y04107*
X03807Y04113*
X03809Y04119*
X0381Y04126*
X03809Y04132*
X03807Y04139*
X03803Y04144*
X03797Y04148*
X03791Y04151*
X03784Y04152*
G37*
G36*
X04754Y04132D02*
X04748Y04131D01*
X04743Y04127*
X04739Y04122*
X04738Y04115*
X04739Y04109*
X04743Y04104*
X04748Y041*
X04754Y04099*
X0476Y041*
X04766Y04104*
X04769Y04109*
X04771Y04115*
X04769Y04122*
X04766Y04127*
X0476Y04131*
X04754Y04132*
G37*
G36*
X02146Y0412D02*
X02139Y04118D01*
X02134Y04115*
X02131Y0411*
X02129Y04103*
X02131Y04097*
X02134Y04092*
X02139Y04088*
X02146Y04087*
X02152Y04088*
X02157Y04092*
X02161Y04097*
X02162Y04103*
X02161Y0411*
X02157Y04115*
X02152Y04118*
X02146Y0412*
G37*
G36*
X0522Y04102D02*
X05214Y04101D01*
X05208Y04098*
X05205Y04092*
X05204Y04086*
X05205Y0408*
X05208Y04075*
X05214Y04071*
X0522Y0407*
X05226Y04071*
X05232Y04075*
X05235Y0408*
X05236Y04086*
X05235Y04092*
X05232Y04098*
X05226Y04101*
X0522Y04102*
G37*
G36*
X02253D02*
X02247Y04101D01*
X02242Y04098*
X02238Y04092*
X02237Y04086*
X02238Y0408*
X02242Y04075*
X02247Y04071*
X02253Y0407*
X0226Y04071*
X02265Y04075*
X02269Y0408*
X0227Y04086*
X02269Y04092*
X02265Y04098*
X0226Y04101*
X02253Y04102*
G37*
G36*
X03504Y04102D02*
X03498Y04101D01*
X03493Y04097*
X03489Y04092*
X03488Y04086*
X03489Y04079*
X03493Y04074*
X03498Y0407*
X03504Y04069*
X03511Y0407*
X03516Y04074*
X03519Y04079*
X03521Y04086*
X03519Y04092*
X03516Y04097*
X03511Y04101*
X03504Y04102*
G37*
G36*
X03294Y04127D02*
X03284Y04126D01*
X03274Y04121*
X03265Y04115*
X03259Y04106*
X03254Y04096*
X03253Y04086*
X03254Y04075*
X03259Y04065*
X03265Y04056*
X03274Y0405*
X03284Y04046*
X03294Y04044*
X03305Y04046*
X03315Y0405*
X03324Y04056*
X0333Y04065*
X03334Y04075*
X03336Y04086*
X03334Y04096*
X0333Y04106*
X03324Y04115*
X03315Y04121*
X03305Y04126*
X03294Y04127*
G37*
G36*
X02994D02*
X02984Y04126D01*
X02974Y04121*
X02965Y04115*
X02959Y04106*
X02954Y04096*
X02953Y04086*
X02954Y04075*
X02959Y04065*
X02965Y04056*
X02974Y0405*
X02984Y04046*
X02994Y04044*
X03005Y04046*
X03015Y0405*
X03024Y04056*
X0303Y04065*
X03034Y04075*
X03036Y04086*
X03034Y04096*
X0303Y04106*
X03024Y04115*
X03015Y04121*
X03005Y04126*
X02994Y04127*
G37*
G36*
X069Y0416D02*
X06887Y04159D01*
X06874Y04155*
X06862Y04149*
X06852Y04141*
X06844Y0413*
X06837Y04119*
X06834Y04106*
X06832Y04093*
X06834Y0408*
X06837Y04067*
X06844Y04056*
X06852Y04045*
X06862Y04037*
X06874Y04031*
X06887Y04027*
X069Y04026*
X06913Y04027*
X06925Y04031*
X06937Y04037*
X06947Y04045*
X06956Y04056*
X06962Y04067*
X06966Y0408*
X06967Y04093*
X06966Y04106*
X06962Y04119*
X06956Y0413*
X06947Y04141*
X06937Y04149*
X06925Y04155*
X06913Y04159*
X069Y0416*
G37*
G36*
X06569D02*
X06556Y04159D01*
X06543Y04155*
X06532Y04149*
X06521Y04141*
X06513Y0413*
X06507Y04119*
X06503Y04106*
X06502Y04093*
X06503Y0408*
X06507Y04067*
X06513Y04056*
X06521Y04045*
X06532Y04037*
X06543Y04031*
X06556Y04027*
X06569Y04026*
X06582Y04027*
X06595Y04031*
X06606Y04037*
X06617Y04045*
X06625Y04056*
X06631Y04067*
X06635Y0408*
X06636Y04093*
X06635Y04106*
X06631Y04119*
X06625Y0413*
X06617Y04141*
X06606Y04149*
X06595Y04155*
X06582Y04159*
X06569Y0416*
G37*
G36*
X02043Y04093D02*
X02034Y04092D01*
X02025Y04088*
X02017Y04083*
X02012Y04075*
X02008Y04067*
X02007Y04057*
X02008Y04048*
X02012Y04039*
X02017Y04032*
X02025Y04026*
X02034Y04023*
X02043Y04022*
X02052Y04023*
X02061Y04026*
X02068Y04032*
X02074Y04039*
X02077Y04048*
X02079Y04057*
X02077Y04067*
X02074Y04075*
X02068Y04083*
X02061Y04088*
X02052Y04092*
X02043Y04093*
G37*
G36*
X00285Y04285D02*
X00264Y04283D01*
X00244Y04278*
X00224Y0427*
X00207Y04259*
X00191Y04246*
X00177Y0423*
X00166Y04212*
X00158Y04193*
X00153Y04172*
X00152Y04152*
X00153Y04131*
X00158Y0411*
X00166Y04091*
X00177Y04073*
X00191Y04057*
X00207Y04044*
X00224Y04033*
X00244Y04025*
X00264Y0402*
X00285Y04018*
X00306Y0402*
X00326Y04025*
X00346Y04033*
X00363Y04044*
X00379Y04057*
X00393Y04073*
X00404Y04091*
X00412Y0411*
X00417Y04131*
X00418Y04152*
X00417Y04172*
X00412Y04193*
X00404Y04212*
X00393Y0423*
X00379Y04246*
X00363Y04259*
X00346Y0427*
X00326Y04278*
X00306Y04283*
X00285Y04285*
G37*
G36*
X01457Y04089D02*
X01448Y04088D01*
X01439Y04084*
X01432Y04079*
X01426Y04071*
X01423Y04063*
X01421Y04053*
X01423Y04044*
X01426Y04036*
X01432Y04028*
X01439Y04022*
X01448Y04019*
X01457Y04018*
X01466Y04019*
X01475Y04022*
X01483Y04028*
X01488Y04036*
X01492Y04044*
X01493Y04053*
X01492Y04063*
X01488Y04071*
X01483Y04079*
X01475Y04084*
X01466Y04088*
X01457Y04089*
G37*
G36*
X01903Y04034D02*
X01897Y04033D01*
X01892Y04029*
X01888Y04024*
X01887Y04018*
X01888Y04011*
X01892Y04006*
X01897Y04002*
X01903Y04001*
X0191Y04002*
X01915Y04006*
X01918Y04011*
X0192Y04018*
X01918Y04024*
X01915Y04029*
X0191Y04033*
X01903Y04034*
G37*
G36*
X02353Y04034D02*
X02347Y04032D01*
X02341Y04029*
X02338Y04023*
X02337Y04017*
X02338Y04011*
X02341Y04006*
X02347Y04002*
X02353Y04001*
X02359Y04002*
X02364Y04006*
X02368Y04011*
X02369Y04017*
X02368Y04023*
X02364Y04029*
X02359Y04032*
X02353Y04034*
G37*
G36*
X05723Y04083D02*
X05708Y04081D01*
X05694Y04075*
X05682Y04066*
X05673Y04054*
X05667Y0404*
X05665Y04025*
X05667Y0401*
X05673Y03996*
X05682Y03984*
X05694Y03975*
X05708Y03969*
X05723Y03967*
X05738Y03969*
X05752Y03975*
X05764Y03984*
X05773Y03996*
X05779Y0401*
X05781Y04025*
X05779Y0404*
X05773Y04054*
X05764Y04066*
X05752Y04075*
X05738Y04081*
X05723Y04083*
G37*
G36*
X01408Y03996D02*
X01402Y03995D01*
X01396Y03991*
X01393Y03986*
X01392Y0398*
X01393Y03974*
X01396Y03968*
X01402Y03965*
X01408Y03964*
X01414Y03965*
X0142Y03968*
X01423Y03974*
X01424Y0398*
X01423Y03986*
X0142Y03991*
X01414Y03995*
X01408Y03996*
G37*
G36*
X04393Y03992D02*
X04387Y03991D01*
X04382Y03987*
X04378Y03982*
X04377Y03976*
X04378Y0397*
X04382Y03964*
X04387Y03961*
X04393Y0396*
X04399Y03961*
X04405Y03964*
X04408Y0397*
X0441Y03976*
X04408Y03982*
X04405Y03987*
X04399Y03991*
X04393Y03992*
G37*
G36*
X02084Y03912D02*
X02078Y03911D01*
X02073Y03907*
X02069Y03902*
X02068Y03896*
X02069Y03889*
X02069Y03889*
X02066Y03885*
X02066Y03886*
X02059Y03887*
X02053Y03886*
X02048Y03882*
X02044Y03877*
X02043Y03871*
X02044Y03864*
X02048Y03859*
X02053Y03855*
X02059Y03854*
X02066Y03855*
X02071Y03859*
X02074Y03864*
X02076Y03871*
X02074Y03877*
X02074Y03877*
X02078Y03881*
X02078Y0388*
X02084Y03879*
X02091Y0388*
X02096Y03884*
X02099Y03889*
X02101Y03896*
X02099Y03902*
X02096Y03907*
X02091Y03911*
X02084Y03912*
G37*
G36*
X02029Y03852D02*
X02023Y03851D01*
X02018Y03847*
X02014Y03842*
X02013Y03836*
X02013Y03835*
X02013Y03834*
X02009Y03831*
X02004Y03832*
X01998Y03831*
X01993Y03827*
X01989Y03822*
X01988Y03816*
X01989Y03809*
X01993Y03804*
X01998Y038*
X02004Y03799*
X02011Y038*
X02016Y03804*
X02019Y03809*
X02021Y03816*
X02021Y03816*
X02021Y03817*
X02025Y0382*
X02029Y03819*
X02036Y0382*
X02041Y03824*
X02044Y03829*
X02046Y03836*
X02044Y03842*
X02041Y03847*
X02036Y03851*
X02029Y03852*
G37*
G36*
X03699D02*
X03693Y03851D01*
X03688Y03847*
X03684Y03842*
X03683Y03836*
X03684Y03829*
X03688Y03824*
X03693Y0382*
X03699Y03819*
X03706Y0382*
X03711Y03824*
X03714Y03829*
X03716Y03836*
X03714Y03842*
X03711Y03847*
X03706Y03851*
X03699Y03852*
G37*
G36*
X03014Y03847D02*
X03008Y03846D01*
X03003Y03842*
X02999Y03837*
X02998Y03831*
X02999Y03824*
X03003Y03819*
X03008Y03815*
X03014Y03814*
X03021Y03815*
X03026Y03819*
X03029Y03824*
X03031Y03831*
X03029Y03837*
X03026Y03842*
X03021Y03846*
X03014Y03847*
G37*
G36*
X03829Y03822D02*
X03823Y03821D01*
X03818Y03817*
X03814Y03812*
X03813Y03806*
X03814Y03799*
X03818Y03794*
X03823Y0379*
X03829Y03789*
X03836Y0379*
X03841Y03794*
X03844Y03799*
X03846Y03806*
X03844Y03812*
X03841Y03817*
X03836Y03821*
X03829Y03822*
G37*
G36*
X03539D02*
X03533Y03821D01*
X03528Y03817*
X03524Y03812*
X03523Y03806*
X03524Y03799*
X03528Y03794*
X03533Y0379*
X03539Y03789*
X03546Y0379*
X03551Y03794*
X03554Y03799*
X03556Y03806*
X03554Y03812*
X03551Y03817*
X03546Y03821*
X03539Y03822*
G37*
G36*
X03219D02*
X03213Y03821D01*
X03208Y03817*
X03204Y03812*
X03203Y03806*
X03204Y03799*
X03208Y03794*
X03213Y0379*
X03219Y03789*
X03226Y0379*
X03231Y03794*
X03234Y03799*
X03236Y03806*
X03234Y03812*
X03231Y03817*
X03226Y03821*
X03219Y03822*
G37*
G36*
X05723Y03902D02*
X05708Y039D01*
X05694Y03894*
X05682Y03885*
X05673Y03873*
X05667Y03859*
X05665Y03844*
X05667Y03829*
X05673Y03815*
X05682Y03803*
X05694Y03794*
X05708Y03788*
X05723Y03786*
X05738Y03788*
X05752Y03794*
X05764Y03803*
X05773Y03815*
X05779Y03829*
X05781Y03844*
X05779Y03859*
X05773Y03873*
X05764Y03885*
X05752Y03894*
X05738Y039*
X05723Y03902*
G37*
G36*
X02722Y03802D02*
X02716Y03801D01*
X0271Y03797*
X02707Y03792*
X02706Y03786*
X02707Y03779*
X0271Y03774*
X02716Y03771*
X02722Y03769*
X02728Y03771*
X02733Y03774*
X02737Y03779*
X02738Y03786*
X02737Y03792*
X02733Y03797*
X02728Y03801*
X02722Y03802*
G37*
G36*
X06169Y03877D02*
X0607D01*
X06055Y03875*
X06041Y03869*
X06029Y0386*
X0602Y03848*
X06014Y03834*
X06012Y03819*
X06014Y03804*
X0602Y0379*
X06029Y03779*
X06041Y03769*
X06055Y03764*
X0607Y03762*
X06169*
X06183Y03764*
X06197Y03769*
X06209Y03779*
X06219Y0379*
X06224Y03804*
X06226Y03819*
X06224Y03834*
X06219Y03848*
X06209Y0386*
X06197Y03869*
X06183Y03875*
X06169Y03877*
G37*
G36*
X04254Y03792D02*
X04248Y03791D01*
X04243Y03787*
X04239Y03782*
X04238Y03776*
X04239Y03769*
X04243Y03764*
X04248Y0376*
X04254Y03759*
X04261Y0376*
X04266Y03764*
X04269Y03769*
X04271Y03776*
X04269Y03782*
X04266Y03787*
X04261Y03791*
X04254Y03792*
G37*
G36*
X069Y03863D02*
X06885Y03861D01*
X06871Y03856*
X06859Y03846*
X0685Y03834*
X06844Y03821*
X06842Y03806*
X06844Y03791*
X0685Y03777*
X06859Y03765*
X06871Y03756*
X06885Y0375*
X069Y03748*
X06915Y0375*
X06929Y03756*
X06941Y03765*
X0695Y03777*
X06955Y03791*
X06957Y03806*
X06955Y03821*
X0695Y03834*
X06941Y03846*
X06929Y03856*
X06915Y03861*
X069Y03863*
G37*
G36*
X06734D02*
X06719Y03861D01*
X06705Y03856*
X06694Y03846*
X06684Y03834*
X06679Y03821*
X06677Y03806*
X06679Y03791*
X06684Y03777*
X06694Y03765*
X06705Y03756*
X06719Y0375*
X06734Y03748*
X06749Y0375*
X06763Y03756*
X06775Y03765*
X06784Y03777*
X0679Y03791*
X06792Y03806*
X0679Y03821*
X06784Y03834*
X06775Y03846*
X06763Y03856*
X06749Y03861*
X06734Y03863*
G37*
G36*
X06569D02*
X06554Y03861D01*
X0654Y03856*
X06528Y03846*
X06519Y03834*
X06513Y03821*
X06511Y03806*
X06513Y03791*
X06519Y03777*
X06528Y03765*
X0654Y03756*
X06554Y0375*
X06569Y03748*
X06584Y0375*
X06598Y03756*
X0661Y03765*
X06619Y03777*
X06625Y03791*
X06627Y03806*
X06625Y03821*
X06619Y03834*
X0661Y03846*
X06598Y03856*
X06584Y03861*
X06569Y03863*
G37*
G36*
X03699Y03767D02*
X03693Y03766D01*
X03688Y03762*
X03684Y03757*
X03683Y03751*
X03684Y03744*
X03688Y03739*
X03693Y03735*
X03699Y03734*
X03706Y03735*
X03711Y03739*
X03714Y03744*
X03716Y03751*
X03714Y03757*
X03711Y03762*
X03706Y03766*
X03699Y03767*
G37*
G36*
X02993D02*
X02987Y03766D01*
X02981Y03762*
X02978Y03757*
X02977Y03751*
X02978Y03744*
X02981Y03739*
X02987Y03735*
X02993Y03734*
X02999Y03735*
X03004Y03739*
X03008Y03744*
X03009Y03751*
X03008Y03757*
X03004Y03762*
X02999Y03766*
X02993Y03767*
G37*
G36*
X06294Y03717D02*
X06288Y03716D01*
X06283Y03712*
X06279Y03707*
X06278Y03701*
X06279Y03694*
X06283Y03689*
X06288Y03685*
X06294Y03684*
X06301Y03685*
X06306Y03689*
X06309Y03694*
X06311Y03701*
X06309Y03707*
X06306Y03712*
X06301Y03716*
X06294Y03717*
G37*
G36*
X01849D02*
X01843Y03716D01*
X01838Y03712*
X01834Y03707*
X01833Y03701*
X01834Y03694*
X01838Y03689*
X01843Y03685*
X01849Y03684*
X01856Y03685*
X01861Y03689*
X01864Y03694*
X01866Y03701*
X01864Y03707*
X01861Y03712*
X01856Y03716*
X01849Y03717*
G37*
G36*
X04437Y03677D02*
X0443Y03676D01*
X04425Y03672*
X04421Y03667*
X0442Y03661*
X04421Y03655*
X04425Y03649*
X0443Y03646*
X04437Y03645*
X04443Y03646*
X04448Y03649*
X04452Y03655*
X04453Y03661*
X04452Y03667*
X04448Y03672*
X04443Y03676*
X04437Y03677*
G37*
G36*
X04385D02*
X04379Y03676D01*
X04374Y03672*
X0437Y03667*
X04369Y03661*
X0437Y03655*
X04374Y03649*
X04379Y03646*
X04385Y03645*
X04392Y03646*
X04397Y03649*
X044Y03655*
X04402Y03661*
X044Y03667*
X04397Y03672*
X04392Y03676*
X04385Y03677*
G37*
G36*
X02679Y03677D02*
X02673Y03676D01*
X02668Y03672*
X02664Y03667*
X02663Y03661*
X02664Y03654*
X02668Y03649*
X02673Y03645*
X02679Y03644*
X02686Y03645*
X02691Y03649*
X02694Y03654*
X02696Y03661*
X02694Y03667*
X02691Y03672*
X02686Y03676*
X02679Y03677*
G37*
G36*
X01754D02*
X01748Y03676D01*
X01743Y03672*
X01739Y03667*
X01738Y03661*
X01739Y03654*
X01743Y03649*
X01748Y03645*
X01754Y03644*
X01761Y03645*
X01766Y03649*
X01769Y03654*
X01771Y03661*
X01769Y03667*
X01766Y03672*
X01761Y03676*
X01754Y03677*
G37*
G36*
X04053Y03657D02*
X04047Y03656D01*
X04042Y03652*
X04038Y03647*
X04037Y03641*
X04038Y03635*
X04042Y03629*
X04047Y03626*
X04053Y03625*
X0406Y03626*
X04065Y03629*
X04068Y03635*
X0407Y03641*
X04068Y03647*
X04065Y03652*
X0406Y03656*
X04053Y03657*
G37*
G36*
X03424Y03652D02*
X03418Y03651D01*
X03413Y03647*
X03409Y03642*
X03408Y03636*
X03409Y03629*
X03413Y03624*
X03418Y0362*
X03424Y03619*
X03431Y0362*
X03436Y03624*
X03439Y03629*
X03441Y03636*
X03439Y03642*
X03436Y03647*
X03431Y03651*
X03424Y03652*
G37*
G36*
X02799Y03632D02*
X02793Y03631D01*
X02788Y03627*
X02784Y03622*
X02783Y03616*
X02784Y03609*
X02788Y03604*
X02793Y036*
X02799Y03599*
X02806Y036*
X02811Y03604*
X02814Y03609*
X02816Y03616*
X02814Y03622*
X02811Y03627*
X02806Y03631*
X02799Y03632*
G37*
G36*
X02139Y03627D02*
X02133Y03626D01*
X02128Y03622*
X02124Y03617*
X02123Y03611*
X02124Y03604*
X02128Y03599*
X02133Y03595*
X02139Y03594*
X02146Y03595*
X02151Y03599*
X02154Y03604*
X02156Y03611*
X02154Y03617*
X02151Y03622*
X02146Y03626*
X02139Y03627*
G37*
G36*
X01884Y03617D02*
X01878Y03616D01*
X01873Y03612*
X01869Y03607*
X01868Y03601*
X01869Y03594*
X01873Y03589*
X01878Y03585*
X01884Y03584*
X01891Y03585*
X01896Y03589*
X01899Y03594*
X01901Y03601*
X01899Y03607*
X01896Y03612*
X01891Y03616*
X01884Y03617*
G37*
G36*
X03239Y03612D02*
X03233Y03611D01*
X03228Y03607*
X03224Y03602*
X03223Y03596*
X03224Y03589*
X03228Y03584*
X03233Y0358*
X03239Y03579*
X03246Y0358*
X03251Y03584*
X03254Y03589*
X03256Y03596*
X03254Y03602*
X03251Y03607*
X03246Y03611*
X03239Y03612*
G37*
G36*
X01549Y03637D02*
X01543Y03636D01*
X01538Y03632*
X01534Y03627*
X01533Y03621*
X01534Y03614*
X01538Y03609*
X01543Y03605*
X01549Y03604*
X01556Y03605*
X01556Y03606*
X01559Y03602*
X01559Y03602*
X01558Y03596*
X01559Y03589*
X01563Y03584*
X01568Y0358*
X01574Y03579*
X01581Y0358*
X01586Y03584*
X01589Y03589*
X01591Y03596*
X01589Y03602*
X01586Y03607*
X01581Y03611*
X01574Y03612*
X01568Y03611*
X01568Y0361*
X01564Y03614*
X01564Y03614*
X01566Y03621*
X01564Y03627*
X01561Y03632*
X01556Y03636*
X01549Y03637*
G37*
G36*
X02422Y03624D02*
X02413Y03623D01*
X02405Y03617*
X024Y0361*
X02398Y03601*
X024Y03592*
X02405Y03584*
X02413Y03579*
X02422Y03577*
X02431Y03579*
X02438Y03584*
X02443Y03592*
X02445Y03601*
X02443Y0361*
X02438Y03617*
X02431Y03623*
X02422Y03624*
G37*
G36*
X02774Y03582D02*
X02768Y03581D01*
X02763Y03577*
X02759Y03572*
X02758Y03566*
X02759Y03559*
X02763Y03554*
X02768Y0355*
X02774Y03549*
X02781Y0355*
X02786Y03554*
X02789Y03559*
X02791Y03566*
X02789Y03572*
X02786Y03577*
X02781Y03581*
X02774Y03582*
G37*
G36*
X0144Y03573D02*
X01434Y03572D01*
X01429Y03568*
X01425Y03563*
X01424Y03557*
X01425Y0355*
X01429Y03545*
X01434Y03541*
X0144Y0354*
X01447Y03541*
X01452Y03545*
X01455Y0355*
X01457Y03557*
X01455Y03563*
X01452Y03568*
X01447Y03572*
X0144Y03573*
G37*
G36*
X05964Y03579D02*
X05955Y03577D01*
X05947Y03572*
X05941Y03564*
X0594Y03555*
X05941Y03545*
X05947Y03537*
X05955Y03532*
X05964Y0353*
X05973Y03532*
X05981Y03537*
X05987Y03545*
X05989Y03555*
X05987Y03564*
X05981Y03572*
X05973Y03577*
X05964Y03579*
G37*
G36*
X02434Y03562D02*
X02428Y03561D01*
X02423Y03557*
X02419Y03552*
X02418Y03546*
X02419Y03539*
X02423Y03534*
X02428Y0353*
X02434Y03529*
X02441Y0353*
X02446Y03534*
X02449Y03539*
X02451Y03546*
X02449Y03552*
X02446Y03557*
X02441Y03561*
X02434Y03562*
G37*
G36*
X02254Y03552D02*
X02248Y03551D01*
X02243Y03547*
X02239Y03542*
X02238Y03536*
X02239Y03529*
X02243Y03524*
X02248Y0352*
X02254Y03519*
X02261Y0352*
X02266Y03524*
X02269Y03529*
X02271Y03536*
X02269Y03542*
X02266Y03547*
X02261Y03551*
X02254Y03552*
G37*
G36*
X05274Y03527D02*
X05268Y03526D01*
X05263Y03522*
X05259Y03517*
X05258Y03511*
X05259Y03504*
X05263Y03499*
X05268Y03495*
X05274Y03494*
X05281Y03495*
X05286Y03499*
X05289Y03504*
X05291Y03511*
X05289Y03517*
X05286Y03522*
X05281Y03526*
X05274Y03527*
G37*
G36*
X04318Y03524D02*
X04312Y03522D01*
X04307Y03519*
X04303Y03514*
X04302Y03507*
X04303Y03501*
X04307Y03496*
X04312Y03492*
X04318Y03491*
X04325Y03492*
X0433Y03496*
X04333Y03501*
X04335Y03507*
X04333Y03514*
X0433Y03519*
X04325Y03522*
X04318Y03524*
G37*
G36*
X03622Y03502D02*
X03616Y03501D01*
X03611Y03497*
X03607Y03492*
X03606Y03486*
X03607Y03479*
X03611Y03474*
X03616Y0347*
X03622Y03469*
X03629Y0347*
X03634Y03474*
X03637Y03479*
X03639Y03486*
X03637Y03492*
X03634Y03497*
X03629Y03501*
X03622Y03502*
G37*
G36*
X02579D02*
X02573Y03501D01*
X02568Y03497*
X02564Y03492*
X02563Y03486*
X02564Y03479*
X02568Y03474*
X02573Y0347*
X02579Y03469*
X02586Y0347*
X02591Y03474*
X02594Y03479*
X02596Y03486*
X02594Y03492*
X02591Y03497*
X02586Y03501*
X02579Y03502*
G37*
G36*
X02389Y03497D02*
X02383Y03496D01*
X02378Y03492*
X02374Y03487*
X02373Y03481*
X02374Y03474*
X02378Y03469*
X02383Y03465*
X02389Y03464*
X02396Y03465*
X02401Y03469*
X02404Y03474*
X02406Y03481*
X02404Y03487*
X02401Y03492*
X02396Y03496*
X02389Y03497*
G37*
G36*
X03437Y03492D02*
X0343Y03491D01*
X03425Y03487*
X03421Y03482*
X0342Y03476*
X03421Y0347*
X03425Y03464*
X0343Y03461*
X03437Y0346*
X03443Y03461*
X03448Y03464*
X03452Y0347*
X03453Y03476*
X03452Y03482*
X03448Y03487*
X03443Y03491*
X03437Y03492*
G37*
G36*
X06509Y03472D02*
X06503Y03471D01*
X06498Y03467*
X06494Y03462*
X06493Y03456*
X06494Y03449*
X06498Y03444*
X06503Y0344*
X06509Y03439*
X06516Y0344*
X06521Y03444*
X06524Y03449*
X06526Y03456*
X06524Y03462*
X06521Y03467*
X06516Y03471*
X06509Y03472*
G37*
G36*
X03469D02*
X03463Y03471D01*
X03458Y03467*
X03454Y03462*
X03453Y03456*
X03454Y03449*
X03458Y03444*
X03463Y0344*
X03469Y03439*
X03476Y0344*
X03481Y03444*
X03484Y03449*
X03486Y03456*
X03484Y03462*
X03481Y03467*
X03476Y03471*
X03469Y03472*
G37*
G36*
X03358Y03464D02*
X03352Y03463D01*
X03347Y03459*
X03343Y03454*
X03342Y03448*
X03343Y03441*
X03347Y03436*
X03352Y03432*
X03358Y03431*
X03365Y03432*
X0337Y03436*
X03373Y03441*
X03374Y03443*
X03379*
X03379Y0344*
X03383Y03435*
X03388Y03431*
X03394Y0343*
X03401Y03431*
X03406Y03435*
X03409Y0344*
X03411Y03447*
X03409Y03453*
X03406Y03458*
X03401Y03462*
X03394Y03463*
X03388Y03462*
X03383Y03458*
X03379Y03453*
X03379Y03451*
X03374*
X03373Y03454*
X0337Y03459*
X03365Y03463*
X03358Y03464*
G37*
G36*
X02422Y03467D02*
X02413Y03465D01*
X02405Y0346*
X024Y03452*
X02398Y03443*
X024Y03434*
X02405Y03427*
X02413Y03422*
X02422Y0342*
X02431Y03422*
X02438Y03427*
X02443Y03434*
X02445Y03443*
X02443Y03452*
X02438Y0346*
X02431Y03465*
X02422Y03467*
G37*
G36*
X06479Y03442D02*
X06473Y03441D01*
X06468Y03437*
X06464Y03432*
X06463Y03426*
X06464Y03419*
X06468Y03414*
X06473Y0341*
X06479Y03409*
X06486Y0341*
X06491Y03414*
X06494Y03419*
X06496Y03426*
X06494Y03432*
X06491Y03437*
X06486Y03441*
X06479Y03442*
G37*
G36*
X02634Y03422D02*
X02628Y03421D01*
X02623Y03417*
X02619Y03412*
X02618Y03406*
X02619Y03399*
X02623Y03394*
X02628Y0339*
X02634Y03389*
X02641Y0339*
X02646Y03394*
X02649Y03399*
X02651Y03406*
X02649Y03412*
X02646Y03417*
X02641Y03421*
X02634Y03422*
G37*
G36*
X06447Y03412D02*
X06441Y03411D01*
X06436Y03407*
X06432Y03402*
X06431Y03396*
X06432Y03389*
X06436Y03384*
X06441Y0338*
X06447Y03379*
X06453Y0338*
X06459Y03384*
X06462Y03389*
X06463Y03396*
X06462Y03402*
X06459Y03407*
X06453Y03411*
X06447Y03412*
G37*
G36*
X0307Y0341D02*
X03064Y03408D01*
X03059Y03405*
X03055Y03399*
X03054Y03393*
X03055Y03387*
X03059Y03382*
X03064Y03378*
X0307Y03377*
X03077Y03378*
X03082Y03382*
X03085Y03387*
X03087Y03393*
X03085Y03399*
X03082Y03405*
X03077Y03408*
X0307Y0341*
G37*
G36*
X06409Y03387D02*
X06403Y03386D01*
X06398Y03382*
X06394Y03377*
X06393Y03371*
X06394Y03364*
X06398Y03359*
X06403Y03355*
X06409Y03354*
X06416Y03355*
X06421Y03359*
X06424Y03364*
X06426Y03371*
X06424Y03377*
X06421Y03382*
X06416Y03386*
X06409Y03387*
G37*
G36*
X04438Y0337D02*
X04432Y03369D01*
X04427Y03366*
X04423Y0336*
X04422Y03354*
X04423Y03348*
X04427Y03342*
X04432Y03339*
X04438Y03338*
X04445Y03339*
X0445Y03342*
X04454Y03348*
X04455Y03354*
X04454Y0336*
X0445Y03366*
X04445Y03369*
X04438Y0337*
G37*
G36*
X03302Y0336D02*
X03296Y03359D01*
X03291Y03355*
X03287Y0335*
X03286Y03344*
X03287Y03337*
X03291Y03332*
X03296Y03328*
X03302Y03327*
X03309Y03328*
X03314Y03332*
X03317Y03337*
X03319Y03344*
X03317Y0335*
X03314Y03355*
X03309Y03359*
X03302Y0336*
G37*
G36*
X06354Y03347D02*
X06348Y03346D01*
X06343Y03342*
X06339Y03337*
X06338Y03331*
X06339Y03324*
X06343Y03319*
X06348Y03316*
X06354Y03314*
X0636Y03316*
X06366Y03319*
X06369Y03324*
X06371Y03331*
X06369Y03337*
X06366Y03342*
X0636Y03346*
X06354Y03347*
G37*
G36*
X03542Y03334D02*
X03536Y03333D01*
X03531Y0333*
X03527Y03324*
X03526Y03318*
X03527Y03312*
X03531Y03307*
X03536Y03303*
X03542Y03302*
X03549Y03303*
X03554Y03307*
X03557Y03312*
X03559Y03318*
X03557Y03324*
X03554Y0333*
X03549Y03333*
X03542Y03334*
G37*
G36*
X03263Y0332D02*
X03257Y03318D01*
X03252Y03315*
X03248Y0331*
X03247Y03303*
X03248Y03297*
X03252Y03292*
X03257Y03288*
X03263Y03287*
X03269Y03288*
X03275Y03292*
X03278Y03297*
X0328Y03303*
X03278Y0331*
X03275Y03315*
X03269Y03318*
X03263Y0332*
G37*
G36*
X03491Y03313D02*
X03485Y03312D01*
X0348Y03308*
X03476Y03303*
X03475Y03297*
X03476Y0329*
X0348Y03285*
X03485Y03281*
X03491Y0328*
X03498Y03281*
X03503Y03285*
X03506Y0329*
X03508Y03297*
X03506Y03303*
X03503Y03308*
X03498Y03312*
X03491Y03313*
G37*
G36*
X03657Y03312D02*
X03651Y03311D01*
X03646Y03307*
X03642Y03302*
X03641Y03296*
X03642Y0329*
X03646Y03284*
X03651Y03281*
X03657Y0328*
X03664Y03281*
X03669Y03284*
X03672Y0329*
X03674Y03296*
X03672Y03302*
X03669Y03307*
X03664Y03311*
X03657Y03312*
G37*
G36*
X06444Y03307D02*
X06438Y03306D01*
X06433Y03302*
X06429Y03297*
X06428Y03291*
X06429Y03284*
X06433Y03279*
X06438Y03275*
X06444Y03274*
X06451Y03275*
X06456Y03279*
X06459Y03284*
X06461Y03291*
X06459Y03297*
X06456Y03302*
X06451Y03306*
X06444Y03307*
G37*
G36*
X0259Y03304D02*
X02584Y03303D01*
X02579Y03299*
X02575Y03294*
X02574Y03288*
X02575Y03281*
X02579Y03276*
X02584Y03272*
X0259Y03271*
X02597Y03272*
X02602Y03276*
X02605Y03281*
X02607Y03288*
X02605Y03294*
X02602Y03299*
X02597Y03303*
X0259Y03304*
G37*
G36*
X03374Y03289D02*
X03368Y03288D01*
X03363Y03284*
X03359Y03279*
X03358Y03273*
X03359Y03266*
X03363Y03261*
X03368Y03257*
X03374Y03256*
X03381Y03257*
X03386Y03261*
X03389Y03266*
X03391Y03273*
X03389Y03279*
X03386Y03284*
X03381Y03288*
X03374Y03289*
G37*
G36*
X06334Y03282D02*
X06328Y03281D01*
X06323Y03277*
X06319Y03272*
X06318Y03266*
X06319Y03259*
X06323Y03254*
X06328Y0325*
X06334Y03249*
X06341Y0325*
X06346Y03254*
X06349Y03259*
X06351Y03266*
X06349Y03272*
X06346Y03277*
X06341Y03281*
X06334Y03282*
G37*
G36*
X03744Y03277D02*
X03738Y03276D01*
X03733Y03272*
X03729Y03267*
X03728Y03261*
X03729Y03254*
X03733Y03249*
X03738Y03245*
X03744Y03244*
X03751Y03245*
X03756Y03249*
X03759Y03254*
X03761Y03261*
X03759Y03267*
X03756Y03272*
X03751Y03276*
X03744Y03277*
G37*
G36*
X02259D02*
X02253Y03276D01*
X02248Y03272*
X02244Y03267*
X02243Y03261*
X02244Y03254*
X02248Y03249*
X02253Y03245*
X02259Y03244*
X02266Y03245*
X02271Y03249*
X02274Y03254*
X02276Y03261*
X02274Y03267*
X02271Y03272*
X02266Y03276*
X02259Y03277*
G37*
G36*
X0323Y03251D02*
X03224Y0325D01*
X03219Y03246*
X03215Y03241*
X03214Y03235*
X03215Y03228*
X03219Y03223*
X03224Y03219*
X0323Y03218*
X03237Y03219*
X03242Y03223*
X03245Y03228*
X03247Y03235*
X03245Y03241*
X03242Y03246*
X03237Y0325*
X0323Y03251*
G37*
G36*
X03806D02*
X038Y0325D01*
X03795Y03246*
X03791Y03241*
X0379Y03235*
X03791Y03228*
X03795Y03223*
X03797Y03222*
X03796Y03216*
X03793Y03216*
X03788Y03212*
X03784Y03207*
X03783Y03201*
X03784Y03194*
X03788Y03189*
X03793Y03185*
X03799Y03184*
X03806Y03185*
X03811Y03189*
X03814Y03194*
X03816Y03201*
X03814Y03207*
X03811Y03212*
X03809Y03214*
X0381Y03219*
X03813Y03219*
X03818Y03223*
X03821Y03228*
X03823Y03235*
X03821Y03241*
X03818Y03246*
X03813Y0325*
X03806Y03251*
G37*
G36*
X02205Y03216D02*
X02199Y03215D01*
X02194Y03211*
X0219Y03206*
X02189Y032*
X0219Y03193*
X02194Y03188*
X02199Y03184*
X02205Y03183*
X02212Y03184*
X02217Y03188*
X0222Y03193*
X02222Y032*
X0222Y03206*
X02217Y03211*
X02212Y03215*
X02205Y03216*
G37*
G36*
X02422Y03263D02*
X02413Y03261D01*
X02405Y03256*
X024Y03248*
X02398Y03239*
X024Y0323*
X02405Y03223*
X02409Y0322*
X02408Y03215*
X02407Y03214*
X02402Y03211*
X02398Y03206*
X02397Y03199*
X02398Y03193*
X02402Y03188*
X02407Y03184*
X02414Y03183*
X0242Y03184*
X02425Y03188*
X02429Y03193*
X0243Y03199*
X02429Y03206*
X02425Y03211*
X02425Y03211*
X02426Y03217*
X02431Y03218*
X02438Y03223*
X02443Y0323*
X02445Y03239*
X02443Y03248*
X02438Y03256*
X02431Y03261*
X02422Y03263*
G37*
G36*
X06262Y03236D02*
X06256Y03235D01*
X06251Y03231*
X06247Y03226*
X06246Y0322*
X06247Y03213*
X06251Y03208*
X06256Y03204*
X06262Y03203*
X06269Y03204*
X06269Y03205*
X06272Y03201*
X06272Y03201*
X06271Y03195*
X06272Y03188*
X06276Y03183*
X06281Y03179*
X06287Y03178*
X06294Y03179*
X06299Y03183*
X06302Y03188*
X06304Y03195*
X06302Y03201*
X06299Y03206*
X06294Y0321*
X06287Y03211*
X06281Y0321*
X06281Y03209*
X06277Y03213*
X06277Y03213*
X06279Y0322*
X06277Y03226*
X06274Y03231*
X06269Y03235*
X06262Y03236*
G37*
G36*
X06439Y03207D02*
X06433Y03206D01*
X06428Y03202*
X06424Y03197*
X06423Y03191*
X06424Y03184*
X06428Y03179*
X06433Y03175*
X06439Y03174*
X06446Y03175*
X06451Y03179*
X06454Y03184*
X06456Y03191*
X06454Y03197*
X06451Y03202*
X06446Y03206*
X06439Y03207*
G37*
G36*
X03188Y03203D02*
X03182Y03202D01*
X03177Y03198*
X03173Y03193*
X03172Y03187*
X03173Y0318*
X03177Y03175*
X03182Y03171*
X03188Y0317*
X03195Y03171*
X032Y03175*
X03204Y0318*
X03205Y03187*
X03204Y03193*
X032Y03198*
X03195Y03202*
X03188Y03203*
G37*
G36*
X02591Y03202D02*
X02585Y03201D01*
X0258Y03197*
X02576Y03192*
X02575Y03186*
X02576Y03179*
X0258Y03174*
X02585Y03171*
X02591Y03169*
X02598Y03171*
X02603Y03174*
X02606Y03179*
X02608Y03186*
X02606Y03192*
X02603Y03197*
X02598Y03201*
X02591Y03202*
G37*
G36*
X02462Y03188D02*
X02456Y03187D01*
X0245Y03183*
X02447Y03178*
X02446Y03172*
X02447Y03166*
X0245Y0316*
X02456Y03157*
X02462Y03155*
X02468Y03157*
X02473Y0316*
X02477Y03166*
X02478Y03172*
X02477Y03178*
X02473Y03183*
X02468Y03187*
X02462Y03188*
G37*
G36*
X03829Y03192D02*
X03823Y03191D01*
X03818Y03187*
X03814Y03182*
X03813Y03176*
X03814Y03169*
X03818Y03164*
X03823Y0316*
X03829Y03159*
X03836Y0316*
X03836Y03161*
X03839Y03157*
X03839Y03157*
X03838Y03151*
X03839Y03144*
X03843Y03139*
X03848Y03135*
X03854Y03134*
X03861Y03135*
X03866Y03139*
X03869Y03144*
X03871Y03151*
X03869Y03157*
X03866Y03162*
X03861Y03166*
X03854Y03167*
X03848Y03166*
X03848Y03165*
X03844Y03169*
X03844Y03169*
X03846Y03176*
X03844Y03182*
X03841Y03187*
X03836Y03191*
X03829Y03192*
G37*
G36*
X06335Y03163D02*
X06329Y03162D01*
X06324Y03158*
X0632Y03153*
X06319Y03147*
X0632Y0314*
X06324Y03135*
X06329Y03132*
X06335Y0313*
X06342Y03132*
X06347Y03135*
X0635Y0314*
X06352Y03147*
X0635Y03153*
X06347Y03158*
X06342Y03162*
X06335Y03163*
G37*
G36*
X01459D02*
X01453Y03162D01*
X01448Y03158*
X01444Y03153*
X01443Y03147*
X01444Y0314*
X01448Y03135*
X01453Y03131*
X01459Y0313*
X01466Y03131*
X01471Y03135*
X01474Y0314*
X01476Y03147*
X01474Y03153*
X01471Y03158*
X01466Y03162*
X01459Y03163*
G37*
G36*
X03275Y03158D02*
X03269Y03156D01*
X03264Y03153*
X0326Y03147*
X03259Y03141*
X0326Y03135*
X03264Y0313*
X03269Y03126*
X03275Y03125*
X03281Y03126*
X03287Y0313*
X0329Y03135*
X03291Y03141*
X0329Y03147*
X03287Y03153*
X03281Y03156*
X03275Y03158*
G37*
G36*
X06304Y03137D02*
X06298Y03136D01*
X06293Y03132*
X06289Y03127*
X06288Y03121*
X06289Y03114*
X06293Y03109*
X06298Y03105*
X06304Y03104*
X06311Y03105*
X06316Y03109*
X06319Y03114*
X06321Y03121*
X06319Y03127*
X06316Y03132*
X06311Y03136*
X06304Y03137*
G37*
G36*
X03939D02*
X03933Y03136D01*
X03928Y03132*
X03924Y03127*
X03923Y03121*
X03924Y03114*
X03928Y03109*
X03933Y03105*
X03939Y03104*
X03946Y03105*
X03951Y03109*
X03954Y03114*
X03956Y03121*
X03954Y03127*
X03951Y03132*
X03946Y03136*
X03939Y03137*
G37*
G36*
X03491Y03119D02*
X03485Y03118D01*
X0348Y03114*
X03476Y03109*
X03475Y03103*
X03476Y03096*
X0348Y03091*
X03485Y03087*
X03491Y03086*
X03498Y03087*
X03503Y03091*
X03506Y03096*
X03508Y03103*
X03506Y03109*
X03503Y03114*
X03498Y03118*
X03491Y03119*
G37*
G36*
X02418Y03134D02*
X02412Y03133D01*
X02407Y0313*
X02403Y03124*
X02402Y03118*
X02403Y03112*
X02407Y03106*
X02408Y03106*
Y031*
X02405Y03098*
X024Y03091*
X02398Y03082*
X024Y03073*
X02405Y03065*
X02413Y0306*
X02422Y03058*
X02431Y0306*
X02438Y03065*
X02443Y03073*
X02445Y03082*
X02443Y03091*
X02438Y03098*
X02432Y03102*
X02431Y03105*
X02431Y03108*
X02433Y03112*
X02435Y03118*
X02433Y03124*
X0243Y0313*
X02424Y03133*
X02418Y03134*
G37*
G36*
X03368Y03066D02*
X03362Y03065D01*
X03357Y03061*
X03353Y03056*
X03352Y0305*
X03353Y03043*
X03357Y03038*
X03362Y03034*
X03368Y03033*
X03375Y03034*
X0338Y03038*
X03383Y03043*
X03385Y0305*
X03383Y03056*
X0338Y03061*
X03375Y03065*
X03368Y03066*
G37*
G36*
X03344Y03012D02*
X03338Y03011D01*
X03333Y03007*
X03329Y03002*
X03328Y02996*
X03329Y02989*
X03333Y02984*
X03338Y0298*
X03344Y02979*
X03351Y0298*
X03356Y02984*
X03359Y02989*
X03361Y02996*
X03359Y03002*
X03356Y03007*
X03351Y03011*
X03344Y03012*
G37*
G36*
X03197Y02986D02*
X03191Y02985D01*
X03186Y02981*
X03182Y02976*
X03181Y0297*
X03182Y02963*
X03186Y02958*
X03191Y02954*
X03197Y02953*
X03204Y02954*
X03209Y02958*
X03212Y02963*
X03214Y0297*
X03212Y02976*
X03209Y02981*
X03204Y02985*
X03197Y02986*
G37*
G36*
X04794Y02824D02*
X04788Y02823D01*
X04782Y02819*
X04779Y02814*
X04777Y02808*
X04779Y02801*
X04782Y02796*
X04788Y02793*
X04794Y02791*
X048Y02793*
X04805Y02796*
X04809Y02801*
X0481Y02808*
X04809Y02814*
X04805Y02819*
X048Y02823*
X04794Y02824*
G37*
G36*
X04503Y02806D02*
X04497Y02804D01*
X04492Y02801*
X04488Y02796*
X04487Y02789*
X04488Y02783*
X04492Y02778*
X04497Y02774*
X04503Y02773*
X04509Y02774*
X04515Y02778*
X04518Y02783*
X04519Y02789*
X04518Y02796*
X04515Y02801*
X04509Y02804*
X04503Y02806*
G37*
G36*
X02146Y02769D02*
X0214Y02768D01*
X02135Y02764*
X02131Y02759*
X0213Y02753*
X02131Y02746*
X02135Y02741*
X0214Y02737*
X02146Y02736*
X02153Y02737*
X02158Y02741*
X02161Y02746*
X02163Y02753*
X02161Y02759*
X02158Y02764*
X02153Y02768*
X02146Y02769*
G37*
G36*
X02692Y02737D02*
X02686Y02736D01*
X02681Y02732*
X02677Y02727*
X02676Y02721*
X02677Y02715*
X02681Y02709*
X02686Y02706*
X02692Y02705*
X02699Y02706*
X02704Y02709*
X02707Y02715*
X02709Y02721*
X02707Y02727*
X02704Y02732*
X02699Y02736*
X02692Y02737*
G37*
G36*
X02394Y02736D02*
X02388Y02735D01*
X02383Y02732*
X02379Y02726*
X02378Y0272*
X02379Y02714*
X02383Y02708*
X02388Y02705*
X02394Y02704*
X024Y02705*
X02406Y02708*
X02409Y02714*
X02411Y0272*
X02409Y02726*
X02406Y02732*
X024Y02735*
X02394Y02736*
G37*
G36*
X02494Y02712D02*
X02488Y02711D01*
X02483Y02707*
X02479Y02702*
X02478Y02696*
X02479Y02689*
X02483Y02684*
X02488Y02681*
X02488Y02679*
Y02678*
X02488Y02675*
X02483Y02672*
X02479Y02667*
X02478Y02661*
X02479Y02654*
X02483Y02649*
X02488Y02645*
X02494Y02644*
X02501Y02645*
X02506Y02649*
X02509Y02654*
X02511Y02661*
X02509Y02667*
X02506Y02672*
X02501Y02675*
X02501Y02678*
Y02679*
X02501Y02681*
X02506Y02684*
X02509Y02689*
X02511Y02696*
X02509Y02702*
X02506Y02707*
X02501Y02711*
X02494Y02712*
G37*
G36*
X02958Y02637D02*
X02952Y02636D01*
X02947Y02632*
X02943Y02627*
X02942Y02621*
X02943Y02614*
X02947Y02609*
X02952Y02605*
X02958Y02604*
X02965Y02605*
X0297Y02609*
X02973Y02614*
X02975Y02621*
X02973Y02627*
X0297Y02632*
X02965Y02636*
X02958Y02637*
G37*
G36*
X02429D02*
X02422Y02636D01*
X02417Y02632*
X02414Y02627*
X02412Y02621*
X02414Y02614*
X02417Y02609*
X02422Y02605*
X02429Y02604*
X02435Y02605*
X0244Y02609*
X02444Y02614*
X02445Y02621*
X02444Y02627*
X0244Y02632*
X02435Y02636*
X02429Y02637*
G37*
G36*
X02252Y02629D02*
X02246Y02628D01*
X0224Y02625*
X02237Y02619*
X02236Y02613*
X02237Y02607*
X0224Y02602*
X02246Y02598*
X02252Y02597*
X02258Y02598*
X02263Y02602*
X02267Y02607*
X02268Y02613*
X02267Y02619*
X02263Y02625*
X02258Y02628*
X02252Y02629*
G37*
G36*
X02821Y02617D02*
X02815Y02616D01*
X0281Y02612*
X02806Y02607*
X02805Y02601*
X02806Y02594*
X0281Y02589*
X02815Y02585*
X02821Y02584*
X02828Y02585*
X02833Y02589*
X02836Y02594*
X02838Y02601*
X02836Y02607*
X02833Y02612*
X02828Y02616*
X02821Y02617*
G37*
G36*
X03623Y02603D02*
X03617Y02602D01*
X03612Y02598*
X03608Y02593*
X03607Y02587*
X03608Y0258*
X03612Y02575*
X03617Y02571*
X03623Y0257*
X0363Y02571*
X03635Y02575*
X03638Y0258*
X0364Y02587*
X03638Y02593*
X03635Y02598*
X0363Y02602*
X03623Y02603*
G37*
G36*
X04298Y02641D02*
X04286Y02639D01*
X04275Y02635*
X04266Y02627*
X04258Y02618*
X04254Y02607*
X04252Y02595*
X04254Y02583*
X04258Y02572*
X04266Y02562*
X04275Y02555*
X04286Y02551*
X04298Y02549*
X0431Y02551*
X04321Y02555*
X04331Y02562*
X04338Y02572*
X04342Y02583*
X04344Y02595*
X04342Y02607*
X04338Y02618*
X04331Y02627*
X04321Y02635*
X0431Y02639*
X04298Y02641*
G37*
G36*
X0418D02*
X04168Y02639D01*
X04157Y02635*
X04148Y02627*
X0414Y02618*
X04136Y02607*
X04134Y02595*
X04136Y02583*
X0414Y02572*
X04148Y02562*
X04157Y02555*
X04168Y02551*
X0418Y02549*
X04192Y02551*
X04203Y02555*
X04212Y02562*
X0422Y02572*
X04224Y02583*
X04226Y02595*
X04224Y02607*
X0422Y02618*
X04212Y02627*
X04203Y02635*
X04192Y02639*
X0418Y02641*
G37*
G36*
X04062D02*
X0405Y02639D01*
X04039Y02635*
X04029Y02627*
X04022Y02618*
X04018Y02607*
X04016Y02595*
X04018Y02583*
X04022Y02572*
X04029Y02562*
X04039Y02555*
X0405Y02551*
X04062Y02549*
X04074Y02551*
X04085Y02555*
X04094Y02562*
X04102Y02572*
X04106Y02583*
X04108Y02595*
X04106Y02607*
X04102Y02618*
X04094Y02627*
X04085Y02635*
X04074Y02639*
X04062Y02641*
G37*
G36*
X0102Y02497D02*
X01014Y02496D01*
X01009Y02492*
X01005Y02487*
X01004Y02481*
X01005Y02474*
X01009Y02469*
X01014Y02465*
X0102Y02464*
X01027Y02465*
X01032Y02469*
X01035Y02474*
X01037Y02481*
X01035Y02487*
X01032Y02492*
X01027Y02496*
X0102Y02497*
G37*
G36*
X06196Y02508D02*
X06187Y02506D01*
X06179Y02501*
X06174Y02493*
X06172Y02484*
X06174Y02474*
X06179Y02466*
X06187Y02461*
X06196Y02459*
X06206Y02461*
X06214Y02466*
X06219Y02474*
X06221Y02484*
X06219Y02493*
X06214Y02501*
X06206Y02506*
X06196Y02508*
G37*
G36*
X02624Y02477D02*
X02618Y02476D01*
X02613Y02472*
X02609Y02467*
X02608Y02461*
X02609Y02454*
X02609Y02454*
X02606Y0245*
X02606Y02451*
X02599Y02452*
X02593Y02451*
X02588Y02447*
X02584Y02442*
X02583Y02436*
X02584Y02431*
X02583Y0243*
X02581Y02427*
X0258Y02427*
X02575Y02428*
X02569Y02427*
X02564Y02423*
X0256Y02418*
X02559Y02412*
X0256Y02405*
X02564Y024*
X02569Y02396*
X02575Y02395*
X02582Y02396*
X02587Y024*
X0259Y02405*
X02592Y02412*
X02591Y02416*
X02591Y02417*
X02594Y0242*
X02595Y0242*
X02599Y02419*
X02606Y0242*
X02611Y02424*
X02614Y02429*
X02616Y02436*
X02614Y02442*
X02614Y02442*
X02618Y02446*
X02618Y02445*
X02624Y02444*
X02631Y02445*
X02636Y02449*
X02639Y02454*
X02641Y02461*
X02639Y02467*
X02636Y02472*
X02631Y02476*
X02624Y02477*
G37*
G36*
X02272Y0248D02*
X02265Y02478D01*
X0226Y02475*
X02256Y0247*
X02255Y02463*
X02256Y02457*
X0226Y02452*
X02265Y02448*
X02272Y02447*
X02278Y02448*
X02283Y02452*
X02287Y02457*
X02288Y02463*
X02287Y0247*
X02283Y02475*
X02278Y02478*
X02272Y0248*
G37*
G36*
X02525Y02479D02*
X02519Y02478D01*
X02514Y02474*
X0251Y02469*
X02509Y02463*
X0251Y02456*
X02514Y02451*
X02519Y02447*
X02525Y02446*
X02532Y02447*
X02537Y02451*
X0254Y02456*
X02542Y02463*
X0254Y02469*
X02537Y02474*
X02532Y02478*
X02525Y02479*
G37*
G36*
X05578Y02534D02*
X05566Y02533D01*
X05555Y02528*
X05545Y02521*
X05538Y02511*
X05533Y025*
X05532Y02489*
X05533Y02477*
X05538Y02466*
X05545Y02456*
X05555Y02449*
X05566Y02444*
X05578Y02443*
X0559Y02444*
X05601Y02449*
X0561Y02456*
X05617Y02466*
X05622Y02477*
X05624Y02489*
X05622Y025*
X05617Y02511*
X0561Y02521*
X05601Y02528*
X0559Y02533*
X05578Y02534*
G37*
G36*
X02948Y02472D02*
X02942Y02471D01*
X02936Y02468*
X02933Y02462*
X02931Y02456*
X02933Y0245*
X02936Y02444*
X02942Y02441*
X02948Y0244*
X02954Y02441*
X02959Y02444*
X02963Y0245*
X02964Y02456*
X02963Y02462*
X02959Y02468*
X02954Y02471*
X02948Y02472*
G37*
G36*
X0299Y02456D02*
X02982Y02455D01*
X02976Y02451*
X02972Y02444*
X0297Y02437*
X02972Y0243*
X02976Y02424*
X02982Y02419*
X0299Y02418*
X02997Y02419*
X03003Y02424*
X03007Y0243*
X03009Y02437*
X03007Y02444*
X03003Y02451*
X02997Y02455*
X0299Y02456*
G37*
G36*
X02202D02*
X02195Y02455D01*
X02189Y02451*
X02185Y02444*
X02183Y02437*
X02185Y0243*
X02189Y02424*
X02195Y02419*
X02202Y02418*
X0221Y02419*
X02216Y02424*
X0222Y0243*
X02221Y02437*
X0222Y02444*
X02216Y02451*
X0221Y02455*
X02202Y02456*
G37*
G36*
X03617Y02552D02*
X03604Y02551D01*
X03591Y02547*
X0358Y02541*
X03569Y02533*
X03561Y02522*
X03555Y02511*
X03551Y02498*
X0355Y02485*
X03551Y02472*
X03555Y02459*
X03561Y02447*
X03569Y02437*
X0358Y02429*
X03591Y02423*
X03604Y02419*
X03617Y02417*
X0363Y02419*
X03643Y02423*
X03654Y02429*
X03665Y02437*
X03673Y02447*
X03679Y02459*
X03683Y02472*
X03684Y02485*
X03683Y02498*
X03679Y02511*
X03673Y02522*
X03665Y02533*
X03654Y02541*
X03643Y02547*
X0363Y02551*
X03617Y02552*
G37*
G36*
X01651D02*
X01638Y02551D01*
X01625Y02547*
X01614Y02541*
X01603Y02533*
X01595Y02522*
X01589Y02511*
X01585Y02498*
X01584Y02485*
X01585Y02472*
X01589Y02459*
X01595Y02447*
X01603Y02437*
X01614Y02429*
X01625Y02423*
X01638Y02419*
X01651Y02417*
X01664Y02419*
X01677Y02423*
X01688Y02429*
X01699Y02437*
X01707Y02447*
X01713Y02459*
X01717Y02472*
X01718Y02485*
X01717Y02498*
X01713Y02511*
X01707Y02522*
X01699Y02533*
X01688Y02541*
X01677Y02547*
X01664Y02551*
X01651Y02552*
G37*
G36*
X00199Y02545D02*
X00187Y02544D01*
X00175Y0254*
X00164Y02534*
X00154Y02526*
X00146Y02516*
X0014Y02505*
X00136Y02493*
X00135Y02481*
X00136Y02468*
X0014Y02456*
X00146Y02445*
X00154Y02435*
X00164Y02427*
X00175Y02421*
X00187Y02417*
X00199Y02416*
X00212Y02417*
X00224Y02421*
X00235Y02427*
X00245Y02435*
X00253Y02445*
X00259Y02456*
X00262Y02468*
X00264Y02481*
X00262Y02493*
X00259Y02505*
X00253Y02516*
X00245Y02526*
X00235Y02534*
X00224Y0254*
X00212Y02544*
X00199Y02545*
G37*
G36*
X02894Y02447D02*
X02888Y02446D01*
X02883Y02442*
X02879Y02437*
X02878Y02431*
X02879Y02424*
X02883Y02419*
X02888Y02415*
X02894Y02414*
X02901Y02415*
X02906Y02419*
X02907*
X02909Y02416*
X02914Y02412*
X0292Y02411*
X02927Y02412*
X02932Y02416*
X02935Y02421*
X02937Y02428*
X02935Y02434*
X02932Y02439*
X02927Y02443*
X0292Y02444*
X02914Y02443*
X02909Y02439*
X02908*
X02906Y02442*
X02901Y02446*
X02894Y02447*
G37*
G36*
X04039Y02422D02*
X04033Y02421D01*
X04028Y02417*
X04024Y02412*
X04023Y02406*
X04024Y02399*
X04028Y02394*
X04033Y0239*
X04039Y02389*
X04046Y0239*
X04051Y02394*
X04054Y02399*
X04056Y02406*
X04054Y02412*
X04051Y02417*
X04046Y02421*
X04039Y02422*
G37*
G36*
X03498Y02357D02*
X03492Y02356D01*
X03487Y02352*
X03483Y02347*
X03482Y02341*
X03483Y02334*
X03487Y02329*
X03492Y02325*
X03498Y02324*
X03505Y02325*
X0351Y02329*
X03513Y02334*
X03515Y02341*
X03513Y02347*
X0351Y02352*
X03505Y02356*
X03498Y02357*
G37*
G36*
X02726Y02309D02*
X0272Y02308D01*
X02715Y02304*
X02713Y02301*
X02709Y02304*
X02702Y02305*
X02696Y02304*
X02691Y023*
X0269Y02299*
X02684Y02299*
X02682Y02302*
X02677Y02306*
X02671Y02307*
X02664Y02306*
X02659Y02302*
X02656Y02297*
X02654Y02291*
X02655Y02289*
X02654Y02288*
X0265Y02285*
X02645Y02286*
X02639Y02285*
X02634Y02281*
X0263Y02276*
X02629Y0227*
X0263Y02264*
X02634Y02258*
X02639Y02255*
X02645Y02254*
X02652Y02255*
X02657Y02258*
X0266Y02264*
X02662Y0227*
X02661Y02272*
X02662Y02273*
X02666Y02275*
X02671Y02274*
X02677Y02275*
X02682Y02279*
X02683Y0228*
X02689Y0228*
X02691Y02277*
X02696Y02273*
X02702Y02272*
X02709Y02273*
X02714Y02277*
X02716Y0228*
X0272Y02277*
X02726Y02276*
X02733Y02277*
X02738Y02281*
X02741Y02286*
X02743Y02293*
X02741Y02299*
X02738Y02304*
X02733Y02308*
X02726Y02309*
G37*
G36*
X02475Y02307D02*
X02469Y02306D01*
X02464Y02302*
X02462Y02299*
X02457Y02297*
X0245Y02298*
X02444Y02297*
X02439Y02293*
X02435Y02288*
X02434Y02282*
X02435Y02275*
X02439Y0227*
X02444Y02266*
X0245Y02265*
X02457Y02266*
X02462Y0227*
X02465Y02275*
X0247Y02275*
X02475Y02274*
X02482Y02275*
X02487Y02279*
X0249Y02284*
X02492Y02291*
X0249Y02297*
X02487Y02302*
X02482Y02306*
X02475Y02307*
G37*
G36*
X02803Y02323D02*
X02797Y02322D01*
X02792Y02318*
X02788Y02313*
X02787Y02307*
X02788Y023*
X02792Y02295*
X02797Y02291*
X02803Y0229*
X0281Y02291*
X02815Y02295*
X02818Y023*
X0282Y02307*
X02818Y02313*
X02815Y02318*
X0281Y02322*
X02803Y02323*
G37*
G36*
X02985Y02303D02*
X02979Y02302D01*
X02974Y02298*
X0297Y02293*
X02969Y02287*
X0297Y0228*
X02974Y02275*
X02979Y02271*
X02985Y0227*
X02992Y02271*
X02997Y02275*
X03Y0228*
X03002Y02287*
X03Y02293*
X02997Y02298*
X02992Y02302*
X02985Y02303*
G37*
G36*
X02942Y02302D02*
X02936Y02301D01*
X02931Y02297*
X02927Y02292*
X02926Y02286*
X02927Y02279*
X02931Y02274*
X02936Y0227*
X02942Y02269*
X02949Y0227*
X02954Y02274*
X02957Y02279*
X02959Y02286*
X02957Y02292*
X02954Y02297*
X02949Y02301*
X02942Y02302*
G37*
G36*
X05327Y02346D02*
X05317Y02345D01*
X05308Y02341*
X053Y02334*
X05294Y02326*
X0529Y02317*
X05288Y02307*
X0529Y02297*
X05294Y02288*
X053Y0228*
X05308Y02273*
X05317Y02269*
X05327Y02268*
X05337Y02269*
X05347Y02273*
X05355Y0228*
X05361Y02288*
X05365Y02297*
X05366Y02307*
X05365Y02317*
X05361Y02326*
X05355Y02334*
X05347Y02341*
X05337Y02345*
X05327Y02346*
G37*
G36*
X04927D02*
X04917Y02345D01*
X04908Y02341*
X049Y02334*
X04894Y02326*
X0489Y02317*
X04888Y02307*
X0489Y02297*
X04894Y02288*
X049Y0228*
X04908Y02273*
X04917Y02269*
X04927Y02268*
X04937Y02269*
X04947Y02273*
X04955Y0228*
X04961Y02288*
X04965Y02297*
X04966Y02307*
X04965Y02317*
X04961Y02326*
X04955Y02334*
X04947Y02341*
X04937Y02345*
X04927Y02346*
G37*
G36*
X04727D02*
X04717Y02345D01*
X04708Y02341*
X047Y02334*
X04694Y02326*
X0469Y02317*
X04688Y02307*
X0469Y02297*
X04694Y02288*
X047Y0228*
X04708Y02273*
X04717Y02269*
X04727Y02268*
X04737Y02269*
X04747Y02273*
X04755Y0228*
X04761Y02288*
X04765Y02297*
X04766Y02307*
X04765Y02317*
X04761Y02326*
X04755Y02334*
X04747Y02341*
X04737Y02345*
X04727Y02346*
G37*
G36*
X04327D02*
X04317Y02345D01*
X04308Y02341*
X043Y02334*
X04294Y02326*
X0429Y02317*
X04288Y02307*
X0429Y02297*
X04294Y02288*
X043Y0228*
X04308Y02273*
X04317Y02269*
X04327Y02268*
X04337Y02269*
X04347Y02273*
X04355Y0228*
X04361Y02288*
X04365Y02297*
X04366Y02307*
X04365Y02317*
X04361Y02326*
X04355Y02334*
X04347Y02341*
X04337Y02345*
X04327Y02346*
G37*
G36*
X02409Y0233D02*
X02403Y02329D01*
X02398Y02325*
X02394Y0232*
X02393Y02314*
X02394Y02307*
X02398Y02302*
X02399Y02301*
Y02295*
X02398Y02294*
X02394Y02289*
X02393Y02283*
X02394Y02276*
X02398Y02271*
X02403Y02267*
X02409Y02266*
X02416Y02267*
X02421Y02271*
X02424Y02276*
X02426Y02283*
X02424Y02289*
X02421Y02294*
X02419Y02295*
Y02301*
X02421Y02302*
X02424Y02307*
X02426Y02314*
X02424Y0232*
X02421Y02325*
X02416Y02329*
X02409Y0233*
G37*
G36*
X02579Y02297D02*
X02573Y02296D01*
X02568Y02292*
X02564Y02287*
X02563Y02281*
X02564Y02274*
X02568Y02269*
X02573Y02265*
X02579Y02264*
X02586Y02265*
X02591Y02269*
X02594Y02274*
X02596Y02281*
X02594Y02287*
X02591Y02292*
X02586Y02296*
X02579Y02297*
G37*
G36*
X03342Y02279D02*
X03336Y02278D01*
X03331Y02274*
X03327Y02269*
X03326Y02263*
X03327Y02256*
X03331Y02251*
X03336Y02247*
X03342Y02246*
X03349Y02247*
X03354Y02251*
X03357Y02256*
X03359Y02263*
X03357Y02269*
X03354Y02274*
X03349Y02278*
X03342Y02279*
G37*
G36*
X02841D02*
X02835Y02278D01*
X0283Y02274*
X02826Y02269*
X02825Y02263*
X02826Y02256*
X0283Y02251*
X02835Y02247*
X02841Y02246*
X02848Y02247*
X02853Y02251*
X02856Y02256*
X02858Y02263*
X02856Y02269*
X02853Y02274*
X02848Y02278*
X02841Y02279*
G37*
G36*
X00996Y02272D02*
X0099Y02271D01*
X00985Y02267*
X00981Y02262*
X0098Y02256*
X00981Y02249*
X00985Y02244*
X0099Y0224*
X00996Y02239*
X01003Y0224*
X01008Y02244*
X01011Y02249*
X01013Y02256*
X01011Y02262*
X01008Y02267*
X01003Y02271*
X00996Y02272*
G37*
G36*
X05634Y02252D02*
X05628Y02251D01*
X05623Y02247*
X05619Y02242*
X05618Y02236*
X05619Y02229*
X05623Y02224*
X05628Y0222*
X05634Y02219*
X05641Y0222*
X05646Y02224*
X05649Y02229*
X05651Y02236*
X05649Y02242*
X05646Y02247*
X05641Y02251*
X05634Y02252*
G37*
G36*
X02499D02*
X02493Y02251D01*
X02488Y02247*
X02484Y02242*
X02483Y02236*
X02484Y02229*
X02488Y02224*
X02493Y0222*
X02499Y02219*
X02506Y0222*
X02511Y02224*
X02514Y02229*
X02516Y02236*
X02514Y02242*
X02511Y02247*
X02506Y02251*
X02499Y02252*
G37*
G36*
X0233Y02231D02*
X02324Y0223D01*
X02319Y02226*
X02315Y02221*
X02314Y02215*
X02315Y02208*
X02319Y02203*
X02324Y02199*
X0233Y02198*
X02337Y02199*
X02342Y02203*
X02345Y02208*
X02347Y02215*
X02345Y02221*
X02342Y02226*
X02337Y0223*
X0233Y02231*
G37*
G36*
X05577Y0223D02*
X05571Y02229D01*
X05566Y02225*
X05562Y0222*
X05561Y02214*
X05562Y02207*
X05566Y02202*
X05571Y02198*
X05577Y02197*
X05584Y02198*
X05589Y02202*
X05592Y02207*
X05594Y02214*
X05592Y0222*
X05589Y02225*
X05584Y02229*
X05577Y0223*
G37*
G36*
X06424Y02197D02*
X06418Y02196D01*
X06413Y02192*
X06409Y02187*
X06408Y02181*
X06409Y02174*
X06413Y02169*
X06418Y02165*
X06424Y02164*
X06431Y02165*
X06436Y02169*
X06439Y02174*
X06441Y02181*
X06439Y02187*
X06436Y02192*
X06431Y02196*
X06424Y02197*
G37*
G36*
X01754Y02142D02*
X01748Y02141D01*
X01743Y02137*
X01739Y02132*
X01738Y02126*
X01739Y02119*
X01743Y02114*
X01748Y0211*
X01754Y02109*
X01761Y0211*
X01766Y02114*
X01769Y02119*
X01771Y02126*
X01769Y02132*
X01766Y02137*
X01761Y02141*
X01754Y02142*
G37*
G36*
X01619Y02137D02*
X01613Y02136D01*
X01608Y02132*
X01604Y02127*
X01603Y02121*
X01604Y02114*
X01608Y02109*
X01613Y02105*
X01619Y02104*
X01626Y02105*
X01631Y02109*
X01634Y02114*
X01636Y02121*
X01634Y02127*
X01631Y02132*
X01626Y02136*
X01619Y02137*
G37*
G36*
X01696Y02115D02*
X01689Y02114D01*
X01682Y02109*
X01678Y02103*
X01677Y02096*
X01678Y02088*
X01682Y02082*
X01689Y02078*
X01696Y02077*
X01703Y02078*
X0171Y02082*
X01714Y02088*
X01715Y02096*
X01714Y02103*
X0171Y02109*
X01703Y02114*
X01696Y02115*
G37*
G36*
X01884Y02087D02*
X01878Y02086D01*
X01873Y02082*
X01869Y02077*
X01868Y02071*
X01869Y02064*
X01873Y02059*
X01878Y02055*
X01884Y02054*
X01891Y02055*
X01896Y02059*
X01899Y02064*
X01901Y02071*
X01899Y02077*
X01896Y02082*
X01891Y02086*
X01884Y02087*
G37*
G36*
X01568Y02084D02*
X01561Y02082D01*
X01556Y02079*
X01553Y02073*
X01551Y02067*
X01553Y02061*
X01556Y02056*
X01561Y02052*
X01568Y02051*
X01574Y02052*
X01579Y02056*
X01583Y02061*
X01584Y02067*
X01583Y02073*
X01579Y02079*
X01574Y02082*
X01568Y02084*
G37*
G36*
X03571Y02115D02*
X03564Y02114D01*
X03557Y02109*
X03553Y02103*
X03552Y02096*
X03553Y02088*
X03557Y02082*
X03564Y02078*
X03565Y02078*
X03565Y02073*
X03565Y02073*
X0356Y02069*
X03556Y02064*
X03555Y02058*
X03556Y02051*
X03558Y02049*
X03559Y02045*
X03558Y02041*
X03556Y02039*
X03555Y02033*
X03556Y02026*
X0356Y02021*
X03565Y02017*
X03571Y02016*
X03578Y02017*
X03583Y02021*
X03586Y02026*
X03588Y02033*
X03586Y02039*
X03585Y02041*
X03583Y02045*
X03585Y02049*
X03586Y02051*
X03588Y02058*
X03586Y02064*
X03583Y02069*
X03578Y02073*
X03577Y02073*
Y02078*
X03578Y02078*
X03584Y02082*
X03589Y02088*
X0359Y02096*
X03589Y02103*
X03584Y02109*
X03578Y02114*
X03571Y02115*
G37*
G36*
X02409Y01983D02*
X02403Y01982D01*
X02398Y01978*
X02394Y01973*
X02393Y01967*
X02394Y0196*
X02396Y01958*
X02392Y01955*
X02391Y01956*
X02384Y01957*
X02378Y01956*
X02373Y01952*
X02369Y01947*
X02368Y01941*
X02369Y01934*
X02373Y01929*
X02378Y01925*
X02384Y01924*
X02391Y01925*
X02396Y01929*
X02399Y01934*
X02401Y01941*
X02399Y01947*
X02398Y01949*
X02402Y01952*
X02403Y01951*
X02409Y0195*
X02416Y01951*
X02421Y01955*
X02424Y0196*
X02426Y01967*
X02424Y01973*
X02421Y01978*
X02416Y01982*
X02409Y01983*
G37*
G36*
X03298Y01987D02*
X03292Y01986D01*
X03287Y01982*
X03283Y01977*
X03282Y01971*
X03283Y01964*
X03287Y01959*
X03292Y01955*
X03298Y01954*
X03305Y01955*
X0331Y01959*
X03313Y01964*
X03315Y01971*
X03313Y01977*
X0331Y01982*
X03305Y01986*
X03298Y01987*
G37*
G36*
X01009Y01972D02*
X01003Y01971D01*
X00998Y01967*
X00994Y01962*
X00993Y01956*
X00994Y01949*
X00998Y01944*
X01003Y0194*
X01009Y01939*
X01016Y0194*
X01021Y01944*
X01024Y01949*
X01026Y01956*
X01024Y01962*
X01021Y01967*
X01016Y01971*
X01009Y01972*
G37*
G36*
X02299Y01932D02*
X02293Y01931D01*
X02288Y01927*
X02284Y01922*
X02283Y01916*
X02284Y01909*
X02288Y01904*
X02293Y019*
X02299Y01899*
X02306Y019*
X02311Y01904*
X02314Y01909*
X02316Y01916*
X02314Y01922*
X02311Y01927*
X02306Y01931*
X02299Y01932*
G37*
G36*
X00199Y0202D02*
X00187Y02019D01*
X00175Y02015*
X00164Y02009*
X00154Y02001*
X00146Y01991*
X0014Y0198*
X00136Y01968*
X00135Y01956*
X00136Y01943*
X0014Y01931*
X00146Y0192*
X00154Y0191*
X00164Y01902*
X00175Y01896*
X00187Y01892*
X00199Y01891*
X00212Y01892*
X00224Y01896*
X00235Y01902*
X00245Y0191*
X00253Y0192*
X00259Y01931*
X00262Y01943*
X00264Y01956*
X00262Y01968*
X00259Y0198*
X00253Y01991*
X00245Y02001*
X00235Y02009*
X00224Y02015*
X00212Y02019*
X00199Y0202*
G37*
G36*
X03554Y01907D02*
X03548Y01906D01*
X03543Y01902*
X03539Y01897*
X03538Y01891*
X03539Y01884*
X03543Y01879*
X03548Y01875*
X03554Y01874*
X03561Y01875*
X03566Y01879*
X03569Y01884*
X03571Y01891*
X03569Y01897*
X03566Y01902*
X03561Y01906*
X03554Y01907*
G37*
G36*
X03392Y01887D02*
X03386Y01886D01*
X03381Y01882*
X03377Y01877*
X03376Y01871*
X03377Y01864*
X03381Y01859*
X03386Y01855*
X03392Y01854*
X03399Y01855*
X03404Y01859*
X03407Y01864*
X03409Y01871*
X03407Y01877*
X03404Y01882*
X03399Y01886*
X03392Y01887*
G37*
G36*
X03439Y01887D02*
X03433Y01886D01*
X03427Y01882*
X03424Y01877*
X03422Y0187*
X03424Y01864*
X03427Y01859*
X03433Y01855*
X03439Y01854*
X03445Y01855*
X0345Y01859*
X03454Y01864*
X03455Y0187*
X03454Y01877*
X0345Y01882*
X03445Y01886*
X03439Y01887*
G37*
G36*
X03804Y01856D02*
X03798Y01855D01*
X03793Y01851*
X03789Y01846*
X03788Y0184*
X03789Y01833*
X03793Y01828*
X03798Y01824*
X03804Y01823*
X03811Y01824*
X03816Y01828*
X03819Y01833*
X03821Y0184*
X03819Y01846*
X03816Y01851*
X03811Y01855*
X03804Y01856*
G37*
G36*
X03329Y01842D02*
X03322Y01841D01*
X03317Y01837*
X03314Y01832*
X03312Y01826*
X03314Y01819*
X03317Y01814*
X03322Y0181*
X03329Y01809*
X03335Y0181*
X0334Y01814*
X03344Y01819*
X03345Y01826*
X03344Y01832*
X0334Y01837*
X03335Y01841*
X03329Y01842*
G37*
G36*
X01393Y01833D02*
X01387Y01832D01*
X01382Y01828*
X01378Y01823*
X01377Y01816*
X01378Y0181*
X01382Y01805*
X01387Y01801*
X01393Y018*
X01399Y01801*
X01405Y01805*
X01408Y0181*
X0141Y01816*
X01408Y01823*
X01405Y01828*
X01399Y01832*
X01393Y01833*
G37*
G36*
X03944Y01832D02*
X03938Y01831D01*
X03933Y01827*
X03929Y01822*
X03928Y01816*
X03929Y01809*
X03933Y01804*
X03938Y018*
X03944Y01799*
X03951Y018*
X03956Y01804*
X03959Y01809*
X03961Y01816*
X03959Y01822*
X03956Y01827*
X03951Y01831*
X03944Y01832*
G37*
G36*
X03056Y01828D02*
X0305Y01826D01*
X03045Y01823*
X03041Y01818*
X0304Y01811*
X03041Y01805*
X03045Y018*
X0305Y01796*
X03056Y01795*
X03063Y01796*
X03068Y018*
X03071Y01805*
X03073Y01811*
X03071Y01818*
X03068Y01823*
X03063Y01826*
X03056Y01828*
G37*
G36*
X01879D02*
X01873Y01826D01*
X01868Y01823*
X01864Y01818*
X01863Y01811*
X01864Y01805*
X01868Y018*
X01873Y01796*
X01879Y01795*
X01886Y01796*
X01891Y018*
X01895Y01805*
X01896Y01811*
X01895Y01818*
X01891Y01823*
X01886Y01826*
X01879Y01828*
G37*
G36*
X04064Y01812D02*
X04058Y01811D01*
X04053Y01807*
X04049Y01802*
X04048Y01796*
X04049Y01789*
X04053Y01784*
X04058Y0178*
X04064Y01779*
X04071Y0178*
X04076Y01784*
X04079Y01789*
X04081Y01796*
X04079Y01802*
X04076Y01807*
X04071Y01811*
X04064Y01812*
G37*
G36*
X02579Y01806D02*
X02573Y01805D01*
X02568Y01801*
X02564Y01796*
X02563Y0179*
X02564Y01783*
X02568Y01778*
X02573Y01774*
X02579Y01773*
X02586Y01774*
X02591Y01778*
X02594Y01783*
X02596Y0179*
X02594Y01796*
X02591Y01801*
X02586Y01805*
X02579Y01806*
G37*
G36*
X02626Y01786D02*
X0262Y01785D01*
X02615Y01781*
X02611Y01776*
X0261Y0177*
X02611Y01763*
X02615Y01758*
X0262Y01754*
X02626Y01753*
X02633Y01754*
X02638Y01758*
X02641Y01763*
X02643Y0177*
X02641Y01776*
X02638Y01781*
X02633Y01785*
X02626Y01786*
G37*
G36*
X03719Y01782D02*
X03713Y01781D01*
X03708Y01777*
X03704Y01772*
X03703Y01766*
X03704Y01759*
X03708Y01754*
X03713Y0175*
X03719Y01749*
X03726Y0175*
X03731Y01754*
X03734Y01759*
X03736Y01766*
X03734Y01772*
X03731Y01777*
X03726Y01781*
X03719Y01782*
G37*
G36*
X02549Y01771D02*
X02543Y0177D01*
X02538Y01766*
X02534Y01761*
X02533Y01755*
X02534Y01748*
X02538Y01743*
X02543Y01739*
X02549Y01738*
X02556Y01739*
X02561Y01743*
X02564Y01748*
X02566Y01755*
X02564Y01761*
X02561Y01766*
X02556Y0177*
X02549Y01771*
G37*
G36*
X04134Y01767D02*
X04128Y01766D01*
X04123Y01762*
X04119Y01757*
X04118Y01751*
X04119Y01744*
X04123Y01739*
X04128Y01735*
X04134Y01734*
X04141Y01735*
X04146Y01739*
X04149Y01744*
X04151Y01751*
X04149Y01757*
X04146Y01762*
X04141Y01766*
X04134Y01767*
G37*
G36*
X02604Y0175D02*
X02598Y01749D01*
X02593Y01745*
X02589Y0174*
X02588Y01734*
X02589Y01727*
X02593Y01722*
X02598Y01718*
X02604Y01717*
X02611Y01718*
X02616Y01722*
X02619Y01727*
X02621Y01734*
X02619Y0174*
X02616Y01745*
X02611Y01749*
X02604Y0175*
G37*
G36*
X03197Y0173D02*
X03191Y01729D01*
X03185Y01725*
X03182Y0172*
X0318Y01714*
X03182Y01707*
X03185Y01702*
X03191Y01698*
X03197Y01697*
X03203Y01698*
X03208Y01702*
X03212Y01707*
X03213Y01714*
X03212Y0172*
X03208Y01725*
X03203Y01729*
X03197Y0173*
G37*
G36*
X03589Y01727D02*
X03583Y01726D01*
X03578Y01722*
X03574Y01717*
X03573Y01711*
X03574Y01704*
X03578Y01699*
X03583Y01695*
X03589Y01694*
X03596Y01695*
X03601Y01699*
X03604Y01704*
X03606Y01711*
X03604Y01717*
X03601Y01722*
X03596Y01726*
X03589Y01727*
G37*
G36*
X01015Y01722D02*
X01009Y0172D01*
X01004Y01717*
X01Y01711*
X00999Y01705*
X01Y01699*
X01004Y01694*
X01009Y0169*
X01015Y01689*
X01021Y0169*
X01027Y01694*
X0103Y01699*
X01032Y01705*
X0103Y01711*
X01027Y01717*
X01021Y0172*
X01015Y01722*
G37*
G36*
X03747Y01696D02*
X03741Y01695D01*
X03736Y01691*
X03732Y01686*
X03731Y01682*
X03726Y01681*
X03724Y01684*
X03718Y01688*
X03712Y01689*
X03706Y01688*
X03701Y01684*
X03697Y01679*
X03696Y01673*
X03697Y01666*
X03701Y01661*
X03706Y01658*
X03712Y01656*
X03718Y01658*
X03724Y01661*
X03727Y01666*
X03728Y0167*
X03733Y01671*
X03736Y01668*
X03741Y01664*
X03747Y01663*
X03753Y01664*
X03758Y01661*
X03758Y01659*
X03762Y01654*
X03767Y01651*
X03773Y01649*
X0378Y01651*
X03785Y01654*
X03788Y01659*
X0379Y01666*
X03788Y01672*
X03785Y01677*
X0378Y01681*
X03773Y01682*
X03767Y01681*
X03763Y01684*
X03762Y01686*
X03759Y01691*
X03753Y01695*
X03747Y01696*
G37*
G36*
X03803Y01707D02*
X03797Y01706D01*
X03792Y01702*
X03788Y01697*
X03787Y01691*
X03788Y01684*
X03792Y01679*
X03797Y01675*
X03803Y01674*
X0381Y01675*
X03815Y01679*
X03818Y01684*
X0382Y01691*
X03818Y01697*
X03815Y01702*
X0381Y01706*
X03803Y01707*
G37*
G36*
X01893Y01702D02*
X01887Y017D01*
X01882Y01697*
X01878Y01691*
X01877Y01685*
X01878Y01679*
X01882Y01674*
X01887Y0167*
X01893Y01669*
X019Y0167*
X01905Y01674*
X01908Y01679*
X0191Y01685*
X01908Y01691*
X01905Y01697*
X019Y017*
X01893Y01702*
G37*
G36*
X01822Y0169D02*
X01816Y01689D01*
X01811Y01685*
X01807Y0168*
X01806Y01674*
X01807Y01667*
X01811Y01662*
X01816Y01658*
X01822Y01657*
X01829Y01658*
X01834Y01662*
X01837Y01667*
X01839Y01674*
X01837Y0168*
X01834Y01685*
X01829Y01689*
X01822Y0169*
G37*
G36*
X03224Y01677D02*
X03218Y01676D01*
X03213Y01672*
X03209Y01667*
X03208Y01661*
X03209Y01655*
X03213Y01649*
X03218Y01646*
X03224Y01645*
X03231Y01646*
X03235Y01649*
X03239Y01649*
X03241Y01649*
X03246Y01645*
X03252Y01644*
X03259Y01645*
X03264Y01649*
X03267Y01654*
X03269Y01661*
X03267Y01667*
X03264Y01672*
X03259Y01676*
X03252Y01677*
X03246Y01676*
X03242Y01673*
X03238Y01672*
X03235Y01673*
X03231Y01676*
X03224Y01677*
G37*
G36*
X02666Y01656D02*
X0266Y01655D01*
X02655Y01651*
X02651Y01646*
X0265Y0164*
X02651Y01635*
X02647Y01631*
X02647Y01631*
X02643Y01632*
X02637Y01631*
X02632Y01627*
X02628Y01622*
X02627Y01616*
X02628Y01609*
X02632Y01604*
X02637Y016*
X02643Y01599*
X0265Y016*
X02655Y01604*
X02658Y01609*
X0266Y01616*
X02659Y0162*
X02662Y01624*
X02663Y01624*
X02666Y01623*
X02673Y01624*
X02678Y01628*
X02681Y01633*
X02683Y0164*
X02681Y01646*
X02678Y01651*
X02673Y01655*
X02666Y01656*
G37*
G36*
X06838Y01674D02*
X06829Y01672D01*
X06821Y01666*
X06815Y01658*
X06814Y01649*
X06815Y0164*
X06821Y01632*
X06829Y01627*
X06838Y01625*
X06847Y01627*
X06855Y01632*
X06861Y0164*
X06863Y01649*
X06861Y01658*
X06855Y01666*
X06847Y01672*
X06838Y01674*
G37*
G36*
X04134Y01667D02*
X04128Y01666D01*
X04123Y01662*
X04119Y01657*
X04118Y01651*
X04119Y01644*
X04123Y01639*
X04128Y01635*
X04133Y01634*
X04135Y01631*
X04136Y01629*
X04136Y01629*
X04134Y01623*
X04136Y01617*
X04139Y01612*
X04145Y01608*
X04151Y01607*
X04157Y01608*
X04161Y01611*
X04164Y01607*
X04164Y01607*
X04163Y01601*
X04164Y01594*
X04168Y01589*
X04173Y01585*
X04179Y01584*
X04186Y01585*
X04191Y01589*
X04194Y01594*
X04196Y01601*
X04194Y01607*
X04191Y01612*
X04186Y01616*
X04179Y01617*
X04173Y01616*
X04169Y01613*
X04166Y01617*
X04166Y01617*
X04167Y01623*
X04166Y01629*
X04162Y01635*
X04157Y01638*
X04152Y01639*
X0415Y01643*
X04149Y01644*
X04149Y01644*
X04151Y01651*
X04149Y01657*
X04146Y01662*
X04141Y01666*
X04134Y01667*
G37*
G36*
X02719Y01607D02*
X02713Y01606D01*
X02708Y01602*
X02704Y01597*
X02703Y01591*
X02704Y01584*
X02708Y01579*
X02713Y01575*
X02719Y01574*
X02726Y01575*
X02731Y01579*
X02734Y01584*
X02736Y01591*
X02734Y01597*
X02731Y01602*
X02726Y01606*
X02719Y01607*
G37*
G36*
X03894Y01582D02*
X03888Y01581D01*
X03883Y01577*
X03879Y01572*
X03878Y01566*
X03879Y01559*
X03883Y01554*
X03888Y0155*
X03894Y01549*
X03901Y0155*
X03906Y01554*
X03909Y01559*
X03911Y01566*
X03909Y01572*
X03906Y01577*
X03901Y01581*
X03894Y01582*
G37*
G36*
X03969Y01568D02*
X03963Y01567D01*
X03958Y01563*
X03954Y01558*
X03953Y01552*
X03954Y01545*
X03958Y0154*
X03963Y01536*
X03969Y01535*
X03976Y01536*
X03978Y01538*
X03983Y01539*
X03985Y01537*
X03988Y01535*
X03994Y01534*
X04001Y01535*
X04006Y01539*
X04009Y01544*
X04011Y01551*
X04009Y01557*
X04006Y01562*
X04001Y01566*
X03994Y01567*
X03988Y01566*
X03986Y01564*
X03981Y01563*
X03979Y01565*
X03976Y01567*
X03969Y01568*
G37*
G36*
X04034Y01562D02*
X04028Y01561D01*
X04023Y01557*
X04019Y01552*
X04018Y01546*
X04019Y01539*
X04023Y01534*
X04028Y0153*
X04034Y01529*
X04041Y0153*
X04046Y01534*
X04049Y01539*
X04051Y01546*
X04049Y01552*
X04046Y01557*
X04041Y01561*
X04034Y01562*
G37*
G36*
X03924Y01552D02*
X03918Y01551D01*
X03913Y01547*
X03909Y01542*
X03908Y01536*
X03909Y01529*
X03913Y01524*
X03918Y0152*
X03924Y01519*
X03931Y0152*
X03936Y01524*
X03939Y01529*
X03941Y01536*
X03939Y01542*
X03936Y01547*
X03931Y01551*
X03924Y01552*
G37*
G36*
X02894Y01577D02*
X02888Y01576D01*
X02883Y01572*
X02879Y01567*
X02878Y01561*
X02879Y01554*
X02883Y01549*
X02888Y01545*
X02894Y01544*
X02901Y01545*
X02901Y01546*
X02904Y01542*
X02904Y01542*
X02903Y01536*
X02904Y01529*
X02908Y01524*
X02913Y0152*
X02919Y01519*
X02926Y0152*
X02931Y01524*
X02934Y01529*
X02936Y01536*
X02934Y01542*
X02931Y01547*
X02926Y01551*
X02919Y01552*
X02913Y01551*
X02913Y0155*
X02909Y01554*
X02909Y01554*
X02911Y01561*
X02909Y01567*
X02906Y01572*
X02901Y01576*
X02894Y01577*
G37*
G36*
X01719Y01552D02*
X01713Y01551D01*
X01708Y01547*
X01704Y01542*
X01703Y01536*
X01704Y01529*
X01708Y01524*
X01713Y0152*
X01719Y01519*
X01726Y0152*
X01731Y01524*
X01734Y01529*
X01736Y01536*
X01734Y01542*
X01731Y01547*
X01726Y01551*
X01719Y01552*
G37*
G36*
X01897Y01532D02*
X01891Y01531D01*
X01885Y01528*
X01882Y01522*
X0188Y01516*
X01882Y0151*
X01885Y01504*
X01891Y01501*
X01897Y015*
X01903Y01501*
X01908Y01504*
X01912Y0151*
X01913Y01516*
X01912Y01522*
X01908Y01528*
X01903Y01531*
X01897Y01532*
G37*
G36*
X04064Y01527D02*
X04058Y01526D01*
X04053Y01522*
X04049Y01517*
X04048Y01511*
X04049Y01504*
X04053Y01499*
X04058Y01495*
X04064Y01494*
X04071Y01495*
X04076Y01499*
X04079Y01504*
X04081Y01511*
X04079Y01517*
X04076Y01522*
X04071Y01526*
X04064Y01527*
G37*
G36*
X03864D02*
X03858Y01526D01*
X03853Y01522*
X03849Y01517*
X03848Y01511*
X03849Y01504*
X03853Y01499*
X03858Y01495*
X03864Y01494*
X03871Y01495*
X03876Y01499*
X03879Y01504*
X03881Y01511*
X03879Y01517*
X03876Y01522*
X03871Y01526*
X03864Y01527*
G37*
G36*
X02274Y01522D02*
X02268Y01521D01*
X02263Y01517*
X02259Y01512*
X02258Y01506*
X02259Y01499*
X02263Y01494*
X02268Y0149*
X02274Y01489*
X02281Y0149*
X02286Y01494*
X02289Y01499*
X02291Y01506*
X02289Y01512*
X02286Y01517*
X02281Y01521*
X02274Y01522*
G37*
G36*
X03834Y01497D02*
X03828Y01496D01*
X03823Y01492*
X03819Y01487*
X03818Y01481*
X03819Y01474*
X03823Y01469*
X03828Y01465*
X03834Y01464*
X03841Y01465*
X03846Y01469*
X03849Y01474*
X03851Y01481*
X03849Y01487*
X03846Y01492*
X03841Y01496*
X03834Y01497*
G37*
G36*
X02694D02*
X02688Y01496D01*
X02683Y01492*
X02679Y01487*
X02678Y01481*
X02679Y01474*
X02683Y01469*
X02688Y01465*
X02694Y01464*
X02701Y01465*
X02706Y01469*
X02709Y01474*
X02711Y01481*
X02709Y01487*
X02706Y01492*
X02701Y01496*
X02694Y01497*
G37*
G36*
X03549Y01457D02*
X03543Y01456D01*
X03538Y01452*
X03534Y01447*
X03533Y01441*
X03534Y01434*
X03538Y01429*
X03543Y01425*
X03549Y01424*
X03556Y01425*
X03561Y01429*
X03564Y01434*
X03566Y01441*
X03564Y01447*
X03561Y01452*
X03556Y01456*
X03549Y01457*
G37*
G36*
X02446Y01453D02*
X0244Y01452D01*
X02435Y01448*
X02431Y01443*
X0243Y01437*
X02431Y0143*
X02435Y01425*
X0244Y01421*
X02446Y0142*
X02453Y01421*
X02458Y01425*
X02461Y0143*
X02463Y01437*
X02461Y01443*
X02458Y01448*
X02453Y01452*
X02446Y01453*
G37*
G36*
X01008Y01446D02*
X01002Y01445D01*
X00997Y01441*
X00993Y01436*
X00992Y0143*
X00993Y01423*
X00997Y01418*
X01002Y01414*
X01008Y01413*
X01015Y01414*
X0102Y01418*
X01023Y01423*
X01025Y0143*
X01023Y01436*
X0102Y01441*
X01015Y01445*
X01008Y01446*
G37*
G36*
X02083Y01427D02*
X02077Y01426D01*
X02072Y01423*
X02068Y01417*
X02067Y01411*
X02068Y01405*
X02068Y01405*
X02066Y01402*
X02065Y01401*
X02059Y01402*
X02053Y01401*
X02048Y01397*
X02044Y01392*
X02043Y01386*
X02044Y01379*
X02048Y01374*
X02053Y0137*
X02059Y01369*
X02066Y0137*
X02071Y01374*
X02074Y01379*
X02076Y01386*
X02074Y01392*
X02074Y01392*
X02076Y01395*
X02078Y01396*
X02083Y01395*
X0209Y01396*
X02095Y014*
X02098Y01405*
X021Y01411*
X02098Y01417*
X02095Y01423*
X0209Y01426*
X02083Y01427*
G37*
G36*
X03407Y01427D02*
X03401Y01426D01*
X03395Y01422*
X03392Y01417*
X0339Y01411*
X03392Y01405*
X03395Y014*
X03391Y01397*
X03386Y01401*
X03379Y01402*
X03373Y01401*
X03368Y01397*
X03364Y01392*
X03363Y01386*
X03364Y01379*
X03368Y01374*
X03373Y0137*
X03379Y01369*
X03385Y0137*
X03388Y01368*
X03389Y01367*
X03388Y01363*
X03389Y01357*
X03392Y01353*
X03392Y01352*
X03389Y01349*
X03388Y01349*
X03386Y01351*
X03379Y01352*
X03373Y01351*
X03368Y01347*
X03364Y01342*
X03363Y01336*
X03364Y01329*
X03368Y01324*
X03373Y0132*
X03379Y01319*
X03386Y0132*
X03391Y01324*
X03394Y01329*
X03396Y01336*
X03394Y01342*
X03392Y01345*
X03392Y01346*
X03395Y0135*
X03396Y01349*
X03398Y01348*
X03404Y01347*
X03411Y01348*
X03416Y01351*
X03419Y01357*
X03421Y01363*
X03419Y01369*
X03416Y01374*
X03411Y01378*
X03404Y01379*
X03399Y01378*
X03396Y0138*
X03395Y01382*
X03396Y01386*
X03394Y01392*
X03391Y01396*
X03395Y01399*
X03401Y01396*
X03407Y01395*
X03413Y01396*
X03418Y01399*
X03422Y01405*
X03423Y01411*
X03422Y01417*
X03418Y01422*
X03413Y01426*
X03407Y01427*
G37*
G36*
X00199Y01495D02*
X00187Y01494D01*
X00175Y0149*
X00164Y01484*
X00154Y01476*
X00146Y01466*
X0014Y01455*
X00136Y01443*
X00135Y01431*
X00136Y01418*
X0014Y01406*
X00146Y01395*
X00154Y01385*
X00164Y01377*
X00175Y01371*
X00187Y01367*
X00199Y01366*
X00212Y01367*
X00224Y01371*
X00235Y01377*
X00245Y01385*
X00253Y01395*
X00259Y01406*
X00262Y01418*
X00264Y01431*
X00262Y01443*
X00259Y01455*
X00253Y01466*
X00245Y01476*
X00235Y01484*
X00224Y0149*
X00212Y01494*
X00199Y01495*
G37*
G36*
X02028Y01377D02*
X02022Y01376D01*
X02017Y01373*
X02013Y01367*
X02012Y01361*
X02013Y01355*
X02013Y01355*
X02011Y01352*
X0201Y01351*
X02004Y01352*
X01998Y01351*
X01993Y01347*
X01989Y01342*
X01988Y01336*
X01989Y01329*
X01993Y01324*
X01998Y0132*
X02004Y01319*
X02011Y0132*
X02016Y01324*
X02019Y01329*
X02021Y01336*
X02019Y01342*
X02019Y01342*
X02021Y01345*
X02023Y01346*
X02028Y01345*
X02035Y01346*
X0204Y0135*
X02043Y01355*
X02045Y01361*
X02043Y01367*
X0204Y01373*
X02035Y01376*
X02028Y01377*
G37*
G36*
X02502Y01332D02*
X02496Y01331D01*
X02491Y01327*
X02487Y01322*
X02486Y01316*
X02487Y01309*
X02491Y01304*
X02496Y013*
X02502Y01299*
X02509Y013*
X02514Y01304*
X02517Y01309*
X02519Y01316*
X02517Y01322*
X02514Y01327*
X02509Y01331*
X02502Y01332*
G37*
G36*
X01696Y01328D02*
X01689Y01326D01*
X01682Y01322*
X01678Y01316*
X01677Y01308*
X01678Y01301*
X01682Y01295*
X01689Y01291*
X01696Y01289*
X01703Y01291*
X0171Y01295*
X01714Y01301*
X01715Y01308*
X01714Y01316*
X0171Y01322*
X01703Y01326*
X01696Y01328*
G37*
G36*
X03571Y01328D02*
X03564Y01326D01*
X03557Y01322*
X03553Y01316*
X03552Y01308*
X03553Y01301*
X03557Y01295*
X03564Y01291*
X03571Y01289*
X03578Y01291*
X03584Y01295*
X03589Y01301*
X0359Y01308*
X03589Y01316*
X03584Y01322*
X03578Y01326*
X03571Y01328*
G37*
G36*
X01798Y0132D02*
X01791Y01319D01*
X01786Y01315*
X01783Y0131*
X01781Y01304*
X01783Y01297*
X01786Y01292*
X01791Y01289*
X01798Y01287*
X01804Y01289*
X01809Y01292*
X01813Y01297*
X01814Y01304*
X01813Y0131*
X01809Y01315*
X01804Y01319*
X01798Y0132*
G37*
G36*
X02206Y01314D02*
X022Y01313D01*
X02195Y01309*
X02191Y01304*
X0219Y01298*
X02191Y01291*
X02195Y01286*
X022Y01282*
X02206Y01281*
X02213Y01282*
X02218Y01286*
X02221Y01291*
X02223Y01298*
X02221Y01304*
X02218Y01309*
X02213Y01313*
X02206Y01314*
G37*
G36*
X01567Y01301D02*
X01561Y013D01*
X01556Y01296*
X01552Y01291*
X01551Y01285*
X01552Y01279*
X01556Y01273*
X01561Y0127*
X01567Y01269*
X01574Y0127*
X01579Y01273*
X01582Y01279*
X01584Y01285*
X01582Y01291*
X01579Y01296*
X01574Y013*
X01567Y01301*
G37*
G36*
X01003Y01193D02*
X00997Y01192D01*
X00992Y01188*
X00988Y01183*
X00987Y01177*
X00988Y0117*
X00992Y01165*
X00997Y01162*
X01003Y0116*
X0101Y01162*
X01015Y01165*
X01019Y0117*
X0102Y01177*
X01019Y01183*
X01015Y01188*
X0101Y01192*
X01003Y01193*
G37*
G36*
X02826Y00992D02*
X0282Y00991D01*
X02815Y00987*
X0281*
X02805Y00991*
X02799Y00992*
X02792Y00991*
X02787Y00987*
X02786Y00986*
X0278*
X02779Y00987*
X02773Y00991*
X02767Y00992*
X02761Y00991*
X02756Y00987*
X02751*
X02746Y00991*
X0274Y00992*
X02733Y00991*
X02728Y00987*
X02727Y00986*
X02721*
X0272Y00987*
X02714Y00991*
X02708Y00992*
X02702Y00991*
X02697Y00987*
X02692*
X02687Y00991*
X02681Y00992*
X02674Y00991*
X02669Y00987*
X02668Y00986*
X02662*
X02661Y00987*
X02655Y00991*
X02649Y00992*
X02643Y00991*
X02638Y00987*
X02633*
X02628Y00991*
X02622Y00992*
X02615Y00991*
X0261Y00987*
X02606Y00982*
X02605Y00976*
X02606Y0097*
X0261Y00964*
X02615Y00961*
X02622Y0096*
X02628Y00961*
X02633Y00964*
X02638*
X02643Y00961*
X02649Y0096*
X02655Y00961*
X02661Y00964*
X02662Y00966*
X02668*
X02669Y00964*
X02674Y00961*
X02681Y0096*
X02687Y00961*
X02692Y00964*
X02697*
X02702Y00961*
X02708Y0096*
X02714Y00961*
X0272Y00964*
X02721Y00966*
X02727*
X02728Y00964*
X02733Y00961*
X0274Y0096*
X02746Y00961*
X02751Y00964*
X02756*
X02761Y00961*
X02767Y0096*
X02773Y00961*
X02779Y00964*
X0278Y00966*
X02786*
X02787Y00964*
X02792Y00961*
X02799Y0096*
X02805Y00961*
X0281Y00964*
X02815*
X0282Y00961*
X02826Y0096*
X02833Y00961*
X02838Y00964*
X02841Y0097*
X02843Y00976*
X02841Y00982*
X02838Y00987*
X02833Y00991*
X02826Y00992*
G37*
G36*
X04366Y01045D02*
X04289D01*
Y00968*
X04366*
Y01045*
G37*
G36*
X05327Y01046D02*
X05317Y01045D01*
X05308Y01041*
X053Y01034*
X05294Y01026*
X0529Y01017*
X05288Y01007*
X0529Y00997*
X05294Y00988*
X053Y0098*
X05308Y00973*
X05317Y00969*
X05327Y00968*
X05337Y00969*
X05347Y00973*
X05355Y0098*
X05361Y00988*
X05365Y00997*
X05366Y01007*
X05365Y01017*
X05361Y01026*
X05355Y01034*
X05347Y01041*
X05337Y01045*
X05327Y01046*
G37*
G36*
X05127D02*
X05117Y01045D01*
X05108Y01041*
X051Y01034*
X05094Y01026*
X0509Y01017*
X05088Y01007*
X0509Y00997*
X05094Y00988*
X051Y0098*
X05108Y00973*
X05117Y00969*
X05127Y00968*
X05137Y00969*
X05147Y00973*
X05155Y0098*
X05161Y00988*
X05165Y00997*
X05166Y01007*
X05165Y01017*
X05161Y01026*
X05155Y01034*
X05147Y01041*
X05137Y01045*
X05127Y01046*
G37*
G36*
X04927D02*
X04917Y01045D01*
X04908Y01041*
X049Y01034*
X04894Y01026*
X0489Y01017*
X04888Y01007*
X0489Y00997*
X04894Y00988*
X049Y0098*
X04908Y00973*
X04917Y00969*
X04927Y00968*
X04937Y00969*
X04947Y00973*
X04955Y0098*
X04961Y00988*
X04965Y00997*
X04966Y01007*
X04965Y01017*
X04961Y01026*
X04955Y01034*
X04947Y01041*
X04937Y01045*
X04927Y01046*
G37*
G36*
X0299Y00976D02*
X02982Y00975D01*
X02976Y00971*
X02972Y00965*
X0297Y00957*
X02972Y0095*
X02976Y00944*
X02982Y00939*
X0299Y00938*
X02997Y00939*
X03003Y00944*
X03007Y0095*
X03009Y00957*
X03007Y00965*
X03003Y00971*
X02997Y00975*
X0299Y00976*
G37*
G36*
X02202D02*
X02195Y00975D01*
X02189Y00971*
X02185Y00965*
X02183Y00957*
X02185Y0095*
X02189Y00944*
X02195Y00939*
X02202Y00938*
X0221Y00939*
X02216Y00944*
X0222Y0095*
X02221Y00957*
X0222Y00965*
X02216Y00971*
X0221Y00975*
X02202Y00976*
G37*
G36*
X02478Y00953D02*
X02472Y00952D01*
X02467Y00948*
X02463Y00943*
X02462Y00937*
X02463Y0093*
X02467Y00925*
X02472Y00921*
X02478Y0092*
X02485Y00921*
X0249Y00925*
X02493Y0093*
X02495Y00937*
X02493Y00943*
X0249Y00948*
X02485Y00952*
X02478Y00953*
G37*
G36*
X01004Y00922D02*
X00998Y00921D01*
X00993Y00917*
X00989Y00912*
X00988Y00906*
X00989Y00899*
X00993Y00894*
X00998Y0089*
X01004Y00889*
X01011Y0089*
X01016Y00894*
X01019Y00899*
X01021Y00906*
X01019Y00912*
X01016Y00917*
X01011Y00921*
X01004Y00922*
G37*
G36*
X03617Y00982D02*
X03604Y00981D01*
X03591Y00977*
X0358Y00971*
X03569Y00963*
X03561Y00952*
X03555Y00941*
X03551Y00928*
X0355Y00915*
X03551Y00902*
X03555Y00889*
X03561Y00877*
X03569Y00867*
X0358Y00859*
X03591Y00853*
X03604Y00849*
X03617Y00847*
X0363Y00849*
X03643Y00853*
X03654Y00859*
X03665Y00867*
X03673Y00877*
X03679Y00889*
X03683Y00902*
X03684Y00915*
X03683Y00928*
X03679Y00941*
X03673Y00952*
X03665Y00963*
X03654Y00971*
X03643Y00977*
X0363Y00981*
X03617Y00982*
G37*
G36*
X01652D02*
X01639Y00981D01*
X01626Y00977*
X01615Y00971*
X01604Y00963*
X01596Y00952*
X0159Y00941*
X01586Y00928*
X01585Y00915*
X01586Y00902*
X0159Y00889*
X01596Y00877*
X01604Y00867*
X01615Y00859*
X01626Y00853*
X01639Y00849*
X01652Y00847*
X01665Y00849*
X01678Y00853*
X01689Y00859*
X017Y00867*
X01708Y00877*
X01714Y00889*
X01718Y00902*
X01719Y00915*
X01718Y00928*
X01714Y00941*
X01708Y00952*
X017Y00963*
X01689Y00971*
X01678Y00977*
X01665Y00981*
X01652Y00982*
G37*
G36*
X05578Y00936D02*
X05566Y00934D01*
X05555Y0093*
X05545Y00923*
X05538Y00913*
X05533Y00902*
X05532Y0089*
X05533Y00878*
X05538Y00867*
X05545Y00858*
X05555Y0085*
X05566Y00846*
X05578Y00844*
X0559Y00846*
X05601Y0085*
X0561Y00858*
X05617Y00867*
X05622Y00878*
X05624Y0089*
X05622Y00902*
X05617Y00913*
X0561Y00923*
X05601Y0093*
X0559Y00934*
X05578Y00936*
G37*
G36*
X03979D02*
X03967Y00934D01*
X03956Y0093*
X03947Y00923*
X03939Y00913*
X03935Y00902*
X03933Y0089*
X03935Y00878*
X03939Y00867*
X03947Y00858*
X03956Y0085*
X03967Y00846*
X03979Y00844*
X03991Y00846*
X04002Y0085*
X04012Y00858*
X04019Y00867*
X04024Y00878*
X04025Y0089*
X04024Y00902*
X04019Y00913*
X04012Y00923*
X04002Y0093*
X03991Y00934*
X03979Y00936*
G37*
G36*
X00199Y0097D02*
X00187Y00969D01*
X00175Y00965*
X00164Y00959*
X00154Y00951*
X00146Y00941*
X0014Y0093*
X00136Y00918*
X00135Y00906*
X00136Y00893*
X0014Y00881*
X00146Y0087*
X00154Y0086*
X00164Y00852*
X00175Y00846*
X00187Y00842*
X00199Y00841*
X00212Y00842*
X00224Y00846*
X00235Y00852*
X00245Y0086*
X00253Y0087*
X00259Y00881*
X00262Y00893*
X00264Y00906*
X00262Y00918*
X00259Y0093*
X00253Y00941*
X00245Y00951*
X00235Y00959*
X00224Y00965*
X00212Y00969*
X00199Y0097*
G37*
G36*
X02759Y00811D02*
X02753Y0081D01*
X02748Y00806*
X02743*
X02738Y0081*
X02732Y00811*
X02726Y0081*
X0272Y00806*
X02717Y00801*
X02715Y00795*
X02717Y00789*
X0272Y00783*
X02726Y0078*
X02732Y00778*
X02738Y0078*
X02743Y00783*
X02748*
X02753Y0078*
X02759Y00778*
X02766Y0078*
X02771Y00783*
X02774Y00789*
X02776Y00795*
X02774Y00801*
X02771Y00806*
X02766Y0081*
X02759Y00811*
G37*
G36*
X02692D02*
X02686Y0081D01*
X02681Y00806*
X02676*
X02671Y0081*
X02665Y00811*
X02659Y0081*
X02653Y00806*
X0265Y00801*
X02649Y00795*
X0265Y00789*
X02653Y00783*
X02659Y0078*
X02665Y00778*
X02671Y0078*
X02676Y00783*
X02681*
X02686Y0078*
X02692Y00778*
X02699Y0078*
X02704Y00783*
X02707Y00789*
X02709Y00795*
X02707Y00801*
X02704Y00806*
X02699Y0081*
X02692Y00811*
G37*
G36*
X02625D02*
X02619Y0081D01*
X02614Y00806*
X02609*
X02604Y0081*
X02598Y00811*
X02592Y0081*
X02586Y00806*
X02583Y00801*
X02582Y00795*
X02583Y00789*
X02586Y00783*
X02592Y0078*
X02598Y00778*
X02604Y0078*
X02609Y00783*
X02614*
X02619Y0078*
X02625Y00778*
X02632Y0078*
X02637Y00783*
X02641Y00789*
X02642Y00795*
X02641Y00801*
X02637Y00806*
X02632Y0081*
X02625Y00811*
G37*
G36*
X02893D02*
X02887Y0081D01*
X02882Y00806*
X0288Y00805*
X02874*
X02873Y00806*
X02868Y0081*
X02862Y00811*
X02855Y0081*
X0285Y00806*
X02847Y00801*
X02847Y00801*
X02841*
X02841Y00801*
X02838Y00806*
X02833Y0081*
X02826Y00811*
X0282Y0081*
X02815Y00806*
X0281*
X02805Y0081*
X02799Y00811*
X02792Y0081*
X02787Y00806*
X02784Y00801*
X02782Y00795*
X02784Y00789*
X02787Y00783*
X02792Y0078*
X02799Y00778*
X02805Y0078*
X0281Y00783*
X02815*
X0282Y0078*
X02826Y00778*
X02833Y0078*
X02838Y00783*
X02841Y00789*
X02841Y00789*
X02847*
X02847Y00789*
X0285Y00783*
X02855Y0078*
X02862Y00778*
X02868Y0078*
X02873Y00783*
X02874Y00785*
X0288*
X02882Y00783*
X02887Y0078*
X02893Y00778*
X02899Y0078*
X02905Y00783*
X02908Y00789*
X0291Y00795*
X02908Y00801*
X02905Y00806*
X02899Y0081*
X02893Y00811*
G37*
G36*
X0099Y00703D02*
X00983Y00702D01*
X00978Y00698*
X00975Y00693*
X00973Y00687*
X00975Y0068*
X00978Y00675*
X00983Y00671*
X0099Y0067*
X00996Y00671*
X01001Y00675*
X01005Y0068*
X01006Y00687*
X01005Y00693*
X01001Y00698*
X00996Y00702*
X0099Y00703*
G37*
G36*
X02469Y00427D02*
X02463Y00426D01*
X02458Y00422*
X02454Y00417*
X02453Y0041*
X02454Y00404*
X02458Y00399*
X02463Y00395*
X02469Y00394*
X02476Y00395*
X02481Y00399*
X02484Y00404*
X02486Y0041*
X02484Y00417*
X02481Y00422*
X02476Y00426*
X02469Y00427*
G37*
G36*
X0298Y00425D02*
X02974Y00424D01*
X02968Y0042*
X02965Y00415*
X02964Y00409*
X02965Y00402*
X02968Y00397*
X02974Y00394*
X0298Y00392*
X02986Y00394*
X02991Y00397*
X02995Y00402*
X02996Y00409*
X02995Y00415*
X02991Y0042*
X02986Y00424*
X0298Y00425*
G37*
G36*
X03019Y00421D02*
X03013Y0042D01*
X03008Y00417*
X03004Y00411*
X03003Y00405*
X03004Y00399*
X03008Y00393*
X03013Y0039*
X03019Y00389*
X03025Y0039*
X03031Y00393*
X03034Y00399*
X03036Y00405*
X03034Y00411*
X03031Y00417*
X03025Y0042*
X03019Y00421*
G37*
G36*
X02821Y00424D02*
X02815Y00422D01*
X0281Y00419*
X02806Y00414*
X02805Y00407*
X02806Y00401*
X0281Y00396*
X02815Y00392*
X02821Y00391*
X02828Y00392*
X02833Y00396*
X02834Y00397*
X02835Y00398*
X0284Y00397*
X02842Y00393*
X02848Y0039*
X02854Y00389*
X0286Y0039*
X02865Y00393*
X02869Y00399*
X0287Y00405*
X02869Y00411*
X02865Y00417*
X0286Y0042*
X02854Y00421*
X02848Y0042*
X02842Y00417*
X02841Y00415*
X02841Y00415*
X02835Y00415*
X02833Y00419*
X02828Y00422*
X02821Y00424*
G37*
G36*
X02704Y00421D02*
X02698Y0042D01*
X02693Y00417*
X02689Y00411*
X02688Y00405*
X02689Y00399*
X02693Y00393*
X02698Y0039*
X02704Y00389*
X0271Y0039*
X02716Y00393*
X02719Y00399*
X02721Y00405*
X02719Y00411*
X02716Y00417*
X0271Y0042*
X02704Y00421*
G37*
G36*
X02665D02*
X02659Y0042D01*
X02653Y00417*
X0265Y00411*
X02649Y00405*
X0265Y00399*
X02653Y00393*
X02659Y0039*
X02665Y00389*
X02671Y0039*
X02676Y00393*
X0268Y00399*
X02681Y00405*
X0268Y00411*
X02676Y00417*
X02671Y0042*
X02665Y00421*
G37*
G36*
X02511D02*
X02505Y0042D01*
X025Y00417*
X02496Y00411*
X02495Y00405*
X02496Y00399*
X025Y00393*
X02505Y0039*
X02511Y00389*
X02518Y0039*
X02523Y00393*
X02526Y00399*
X02528Y00405*
X02526Y00411*
X02523Y00417*
X02518Y0042*
X02511Y00421*
G37*
G36*
X02389D02*
X02383Y0042D01*
X02378Y00417*
X02374Y00411*
X02373Y00405*
X02374Y00399*
X02378Y00393*
X02383Y0039*
X02389Y00389*
X02396Y0039*
X02401Y00393*
X02404Y00399*
X02406Y00405*
X02404Y00411*
X02401Y00417*
X02396Y0042*
X02389Y00421*
G37*
G36*
X0235D02*
X02344Y0042D01*
X02338Y00417*
X02335Y00411*
X02334Y00405*
X02335Y00399*
X02338Y00393*
X02344Y0039*
X0235Y00389*
X02356Y0039*
X02361Y00393*
X02365Y00399*
X02366Y00405*
X02365Y00411*
X02361Y00417*
X02356Y0042*
X0235Y00421*
G37*
G36*
X01872Y00303D02*
X01865Y00302D01*
X01862Y003*
X01858Y00302*
X01852Y00303*
X01846Y00302*
X01842Y003*
X01838Y00302*
X01832Y00303*
X01826Y00302*
X01821Y00298*
X01817Y00293*
X01816Y00287*
X01817Y00281*
X01821Y00275*
X01822Y00274*
Y00268*
X01821Y00267*
X01817Y00262*
X01816Y00255*
X01817Y00249*
X01821Y00244*
X01826Y0024*
X01832Y00239*
X01838Y0024*
X01842Y00243*
X01846Y0024*
X01852Y00239*
X01858Y0024*
X01862Y00243*
X01865Y0024*
X01872Y00239*
X01878Y0024*
X01883Y00244*
X01887Y00249*
X01888Y00255*
X01887Y00262*
X01883Y00267*
X01881Y00268*
Y00274*
X01883Y00275*
X01887Y00281*
X01888Y00287*
X01887Y00293*
X01883Y00298*
X01878Y00302*
X01872Y00303*
G37*
G36*
X02112D02*
X02105Y00302D01*
X021Y00298*
X02097Y00293*
X02097Y00293*
X02091*
X02091Y00293*
X02088Y00298*
X02083Y00302*
X02076Y00303*
X0207Y00302*
X02065Y00298*
X02061Y00293*
X0206Y00287*
X02061Y00281*
X02065Y00275*
X02067Y00274*
Y00268*
X02065Y00267*
X02061Y00262*
X0206Y00255*
X02061Y00249*
X02065Y00244*
X0207Y0024*
X02076Y00239*
X02083Y0024*
X02088Y00244*
X02091Y00249*
X02091Y0025*
X02097*
X02097Y00249*
X021Y00244*
X02105Y0024*
X02112Y00239*
X02118Y0024*
X02123Y00244*
X02127Y00249*
X02128Y00255*
X02127Y00262*
X02123Y00267*
X02121Y00268*
Y00274*
X02123Y00275*
X02127Y00281*
X02128Y00287*
X02127Y00293*
X02123Y00298*
X02118Y00302*
X02112Y00303*
G37*
G36*
X0261Y00295D02*
X02603Y00294D01*
X02598Y00291*
X02597Y00289*
X02591*
X0259Y00291*
X02584Y00294*
X02578Y00295*
X02572Y00294*
X02567Y00291*
X02563Y00285*
X02562Y00279*
X02563Y00273*
X02567Y00267*
X02572Y00264*
X02578Y00263*
X02584Y00264*
X0259Y00267*
X02591Y00269*
X02597*
X02598Y00267*
X02603Y00264*
X0261Y00263*
X02616Y00264*
X02621Y00267*
X02625Y00273*
X02626Y00279*
X02625Y00285*
X02621Y00291*
X02616Y00294*
X0261Y00295*
G37*
G36*
X02444D02*
X02438Y00294D01*
X02433Y00291*
X02432Y00289*
X02426*
X02424Y00291*
X02419Y00294*
X02413Y00295*
X02407Y00294*
X02401Y00291*
X02398Y00285*
X02397Y00279*
X02398Y00273*
X02401Y00267*
X02407Y00264*
X02413Y00263*
X02419Y00264*
X02424Y00267*
X02426Y00269*
X02432*
X02433Y00267*
X02438Y00264*
X02444Y00263*
X02451Y00264*
X02456Y00267*
X02459Y00273*
X02461Y00279*
X02459Y00285*
X02456Y00291*
X02451Y00294*
X02444Y00295*
G37*
G36*
X02937D02*
X0293Y00294D01*
X02925Y00291*
X02924Y00289*
X02918*
X02917Y00291*
X02911Y00294*
X02905Y00295*
X02899Y00294*
X02893Y00291*
X0289Y00285*
X02889Y00279*
X0289Y00273*
X02893Y00267*
X02899Y00264*
X02905Y00263*
X02911Y00264*
X02917Y00267*
X02918Y00269*
X02924*
X02925Y00267*
X0293Y00264*
X02937Y00263*
X02943Y00264*
X02948Y00267*
X02952Y00273*
X02953Y00279*
X02952Y00285*
X02948Y00291*
X02943Y00294*
X02937Y00295*
G37*
G36*
X02748Y00298D02*
X02742Y00297D01*
X02737Y00293*
X02733Y00288*
X02732Y00282*
X02733Y00276*
X02737Y0027*
X02742Y00267*
X02748Y00266*
X02755Y00267*
X0276Y0027*
X02766Y0027*
X02767Y00267*
X02773Y00264*
X02779Y00263*
X02785Y00264*
X02791Y00267*
X02794Y00273*
X02795Y00279*
X02794Y00285*
X02791Y00291*
X02785Y00294*
X02779Y00295*
X02773Y00294*
X02767Y00291*
X02762Y00291*
X0276Y00293*
X02755Y00297*
X02748Y00298*
G37*
G36*
X02151Y00303D02*
X02145Y00302D01*
X0214Y00298*
X02136Y00293*
X02135Y00287*
X02136Y00281*
X0214Y00275*
X02141Y00274*
Y00268*
X0214Y00267*
X02136Y00262*
X02135Y00255*
X02136Y00249*
X0214Y00244*
X02145Y0024*
X02151Y00239*
X02157Y0024*
X02163Y00244*
X02166Y00249*
X02167Y00255*
X02166Y00262*
X02163Y00267*
X02161Y00268*
Y00274*
X02163Y00275*
X02166Y00281*
X02167Y00287*
X02166Y00293*
X02163Y00298*
X02157Y00302*
X02151Y00303*
G37*
G36*
X00285Y00501D02*
X00264Y00499D01*
X00244Y00494*
X00224Y00486*
X00207Y00476*
X00191Y00462*
X00177Y00446*
X00166Y00428*
X00158Y00409*
X00153Y00388*
X00152Y00368*
X00153Y00347*
X00158Y00326*
X00166Y00307*
X00177Y00289*
X00191Y00273*
X00207Y0026*
X00224Y00249*
X00244Y00241*
X00264Y00236*
X00285Y00234*
X00306Y00236*
X00326Y00241*
X00346Y00249*
X00363Y0026*
X00379Y00273*
X00393Y00289*
X00404Y00307*
X00412Y00326*
X00417Y00347*
X00418Y00368*
X00417Y00388*
X00412Y00409*
X00404Y00428*
X00393Y00446*
X00379Y00462*
X00363Y00476*
X00346Y00486*
X00326Y00494*
X00306Y00499*
X00285Y00501*
G37*
%LNtimingcard_pcb-3*%
%LPD*%
G54D142*
X00299Y02581D03*
Y02381D03*
X00099D03*
Y02581D03*
X00299Y02056D03*
Y01856D03*
X00099D03*
Y02056D03*
X00299Y01531D03*
Y01331D03*
X00099D03*
Y01531D03*
X00299Y01006D03*
Y00806D03*
X00099D03*
Y01006D03*
G54D170*
X05127Y02307D03*
G54D172*
X03979Y02489D03*
X05578Y01689D03*
G54D173*
X06569Y03589D03*
X06734D03*
X069D03*
G54D175*
X06119Y04056D03*
G54D176*
X05934Y03937D03*
G54D181*
X02618Y02299D03*
X06978Y0183D03*
X02314Y00933D03*
X02413D03*
X02515D03*
X02905Y00937D03*
X02901Y01106D03*
X0285D03*
X02787D03*
X02728D03*
X02665D03*
X0261D03*
X02511Y01105D03*
X02409Y01106D03*
X02311D03*
X02322Y02429D03*
X02421D03*
X02484D03*
X02783Y02433D03*
X02874Y0229D03*
X02779Y02601D03*
X02688D03*
X0259D03*
X02488Y02574D03*
X02385Y02613D03*
X02279Y02614D03*
X03051Y02732D03*
X03414Y02892D03*
Y02736D03*
X04116Y03597D03*
X03718Y01713D03*
X0359Y01662D03*
X04523Y03736D03*
X0333Y03301D03*
X01721Y01685D03*
X0167D03*
X03877Y03078D03*
X02633Y02921D03*
X02413Y03295D03*
X02258Y03741D03*
X0272Y03494D03*
X06274Y02949D03*
X06362Y02952D03*
X0645Y02462D03*
Y02535D03*
X06452Y02606D03*
X06451Y02673D03*
X0645Y0274D03*
X06587Y01529D03*
X06594Y01673D03*
Y0161D03*
Y01775D03*
Y0172D03*
X03602Y00641D03*
X01674Y01989D03*
X03732Y01418D03*
X03719Y01996D03*
X02685Y02311D03*
X01714Y01595D03*
X02606Y00931D03*
X02881Y02566D03*
X03554Y01941D03*
X0341Y01713D03*
X03414Y01805D03*
X01718Y01792D03*
X03719Y01921D03*
X01675Y01891D03*
X03554Y01991D03*
X03594Y01514D03*
X03406Y01461D03*
X01718Y01497D03*
X01671Y01792D03*
Y01399D03*
X0167Y01595D03*
X01716Y01399D03*
X01671Y01497D03*
X03413Y01573D03*
X01721Y01989D03*
Y0189D03*
X03549Y01413D03*
X03554Y01841D03*
X04039Y03784D03*
X02878Y00249D03*
X02957Y00251D03*
X02447Y00242D03*
X02636Y00247D03*
X02799Y00251D03*
X02546Y00244D03*
X03097Y00251D03*
X02034Y00246D03*
X01916Y00244D03*
X02309Y00246D03*
X03183Y03135D03*
X03277Y02963D03*
X02419Y02788D03*
X02321Y03361D03*
X02473Y0298D03*
X00937Y02317D03*
X01726Y04329D03*
X01788D03*
X04477Y03135D03*
X04064Y02722D03*
X06628Y01372D03*
X03968Y01671D03*
X04131Y01686D03*
X03996Y01711D03*
X0396Y02724D03*
X06647Y03129D03*
X04339Y02725D03*
X0383Y03762D03*
X03395Y04222D03*
X04272Y03135D03*
X04208D03*
X06649Y03003D03*
X04152Y03135D03*
X01248Y02D03*
X04068Y03135D03*
X02674Y03501D03*
X04234Y02725D03*
X06456Y03009D03*
X01691Y04079D03*
X06476Y03231D03*
X04333Y03135D03*
X01261Y02482D03*
X04114Y03135D03*
X06648Y03341D03*
X02888Y04221D03*
X01749Y0411D03*
X0229Y04217D03*
X03744Y03342D03*
X03717Y03072D03*
X05733Y03556D03*
X05676Y03546D03*
X03603Y00682D03*
X06694Y0183D03*
X06699Y01881D03*
X06949Y02095D03*
X06607Y02176D03*
X06395Y02111D03*
X06048Y02171D03*
X06003Y0243D03*
X06274Y02391D03*
X0491Y04203D03*
X04387Y04206D03*
X03777Y04023D03*
X04085Y03892D03*
X04194Y03884D03*
X04431Y03135D03*
X0286Y03787D03*
X02724Y03729D03*
X03531Y0366D03*
X03269Y03788D03*
X01242Y01472D03*
X01256Y00942D03*
X00654Y0079D03*
X00655Y01028D03*
X00654Y01314D03*
X00653Y01551D03*
X00654Y01839D03*
Y02073D03*
Y02365D03*
X00653Y02593D03*
G54D183*
X02531Y03853D03*
Y0283D03*
X00149D03*
Y03853D03*
M02*